FILE_TYPE = MACRO_DRAWING;
SET COLOR_WIRE YELLOW;
SET COLOR_PROP ORANGE;
SET COLOR_DOT WHITE;
SET COLOR_ARC YELLOW;
SET COLOR_BODY GREEN;
SET COLOR_NOTE PURPLE;
SET PROP_DISPLAY VALUE;
SET PAGE_NUMBER P64;
FORCEADD OFFPAGE..1
(-1350 3950);
FORCEPROP 2 LAST $XR0 32 
J 0
(-1571 3950);
DISPLAY 0.638298 (-1571 3950);
PAINT MONO (-1571 3950);
FORCEPROP 2 LAST CDS_LIB standard
J 0
(-1350 3950);
PAINT MONO (-1350 3950);
DISPLAY INVISIBLE (-1350 3950);
FORCEPROP 1 LAST OFFPAGE TRUE
J 0
(-1025 3825);
DISPLAY 0.872340 (-1025 3825);
DISPLAY INVISIBLE (-1025 3825);
FORCEPROP 1 LAST COMMENT_BODY TRUE
J 0
(-1225 3850);
DISPLAY 0.872340 (-1225 3850);
PAINT GREEN (-1225 3850);
DISPLAY INVISIBLE (-1225 3850);
FORCEPROP 2 LAST PATH I1
J 0
(-1300 4025);
DISPLAY 1.021277 (-1300 4025);
DISPLAY INVISIBLE (-1300 4025);
FORCEADD OFFPAGE..2
(4475 2700);
FORCEPROP 2 LAST $XR0 32 
J 0
(4664 2700);
DISPLAY 0.638298 (4664 2700);
PAINT MONO (4664 2700);
FORCEPROP 2 LAST CDS_LIB standard
J 0
(4475 2700);
PAINT MONO (4475 2700);
DISPLAY INVISIBLE (4475 2700);
FORCEPROP 1 LAST OFFPAGE TRUE
J 0
(4800 2575);
DISPLAY 1.170213 (4800 2575);
PAINT GREEN (4800 2575);
DISPLAY INVISIBLE (4800 2575);
FORCEPROP 1 LAST COMMENT_BODY TRUE
J 0
(4430 2605);
DISPLAY 1.170213 (4430 2605);
PAINT GREEN (4430 2605);
DISPLAY INVISIBLE (4430 2605);
FORCEPROP 2 LAST PATH I100
J 0
(4650 2775);
DISPLAY 1.021277 (4650 2775);
DISPLAY INVISIBLE (4650 2775);
FORCEADD OFFPAGE..2
(4475 3950);
FORCEPROP 2 LAST $XR0 32 
J 0
(4664 3950);
DISPLAY 0.638298 (4664 3950);
PAINT MONO (4664 3950);
FORCEPROP 2 LAST CDS_LIB standard
J 0
(4475 3950);
PAINT MONO (4475 3950);
DISPLAY INVISIBLE (4475 3950);
FORCEPROP 1 LAST OFFPAGE TRUE
J 0
(4800 3825);
DISPLAY 1.170213 (4800 3825);
PAINT GREEN (4800 3825);
DISPLAY INVISIBLE (4800 3825);
FORCEPROP 1 LAST COMMENT_BODY TRUE
J 0
(4430 3855);
DISPLAY 1.170213 (4430 3855);
PAINT GREEN (4430 3855);
DISPLAY INVISIBLE (4430 3855);
FORCEPROP 2 LAST PATH I101
J 0
(4650 4025);
DISPLAY 1.021277 (4650 4025);
DISPLAY INVISIBLE (4650 4025);
FORCEADD TAP..1
R 2
(-100 3875);
FORCEPROP 3 LASTPIN (-50 3875) SIG_NAME UPI_CPU0_CPU1_P0P1_DP<22>
J 0
(-40 3885);
DISPLAY 0.659574 (-40 3885);
PAINT MONO (-40 3885);
DISPLAY INVISIBLE (-40 3885);
FORCEPROP 1 LASTPIN (-50 3875) BN 22
J 2
(-38 3883);
DISPLAY 0.680851 (-38 3883);
PAINT GREEN (-38 3883);
FORCEPROP 2 LAST CDS_LIB standard
J 0
(-100 3875);
DISPLAY INVISIBLE (-100 3875);
FORCEPROP 1 LAST BODY_TYPE PLUMBING
J 2
(-100 3925);
DISPLAY 0.872340 (-100 3925);
PAINT GREEN (-100 3925);
DISPLAY INVISIBLE (-100 3925);
FORCEPROP 1 LAST HDL_TAP TRUE
J 2
(-425 3750);
DISPLAY 0.872340 (-425 3750);
DISPLAY INVISIBLE (-425 3750);
FORCEPROP 1 LAST PATH I102
J 2
(-98 3875);
DISPLAY 0.872340 (-98 3875);
PAINT GREEN (-98 3875);
DISPLAY INVISIBLE (-98 3875);
FORCEADD TAP..1
R 2
(-100 3825);
FORCEPROP 3 LASTPIN (-50 3825) SIG_NAME UPI_CPU0_CPU1_P0P1_DP<21>
J 0
(-40 3835);
DISPLAY 0.659574 (-40 3835);
PAINT MONO (-40 3835);
DISPLAY INVISIBLE (-40 3835);
FORCEPROP 1 LASTPIN (-50 3825) BN 21
J 2
(-38 3833);
DISPLAY 0.680851 (-38 3833);
PAINT GREEN (-38 3833);
FORCEPROP 2 LAST CDS_LIB standard
J 0
(-100 3825);
DISPLAY INVISIBLE (-100 3825);
FORCEPROP 1 LAST BODY_TYPE PLUMBING
J 2
(-100 3875);
DISPLAY 0.872340 (-100 3875);
PAINT GREEN (-100 3875);
DISPLAY INVISIBLE (-100 3875);
FORCEPROP 1 LAST HDL_TAP TRUE
J 2
(-425 3700);
DISPLAY 0.872340 (-425 3700);
DISPLAY INVISIBLE (-425 3700);
FORCEPROP 1 LAST PATH I103
J 2
(-98 3825);
DISPLAY 0.872340 (-98 3825);
PAINT GREEN (-98 3825);
DISPLAY INVISIBLE (-98 3825);
FORCEADD TAP..1
R 2
(-100 3775);
FORCEPROP 3 LASTPIN (-50 3775) SIG_NAME UPI_CPU0_CPU1_P0P1_DP<20>
J 0
(-40 3785);
DISPLAY 0.659574 (-40 3785);
PAINT MONO (-40 3785);
DISPLAY INVISIBLE (-40 3785);
FORCEPROP 1 LASTPIN (-50 3775) BN 20
J 2
(-38 3783);
DISPLAY 0.680851 (-38 3783);
PAINT GREEN (-38 3783);
FORCEPROP 2 LAST CDS_LIB standard
J 0
(-100 3775);
DISPLAY INVISIBLE (-100 3775);
FORCEPROP 1 LAST BODY_TYPE PLUMBING
J 2
(-100 3825);
DISPLAY 0.872340 (-100 3825);
PAINT GREEN (-100 3825);
DISPLAY INVISIBLE (-100 3825);
FORCEPROP 1 LAST HDL_TAP TRUE
J 2
(-425 3650);
DISPLAY 0.872340 (-425 3650);
DISPLAY INVISIBLE (-425 3650);
FORCEPROP 1 LAST PATH I104
J 2
(-98 3775);
DISPLAY 0.872340 (-98 3775);
PAINT GREEN (-98 3775);
DISPLAY INVISIBLE (-98 3775);
FORCEADD TAP..1
R 2
(-100 3525);
FORCEPROP 3 LASTPIN (-50 3525) SIG_NAME UPI_CPU0_CPU1_P0P1_DP<15>
J 0
(-40 3535);
DISPLAY 0.659574 (-40 3535);
PAINT MONO (-40 3535);
DISPLAY INVISIBLE (-40 3535);
FORCEPROP 1 LASTPIN (-50 3525) BN 15
J 2
(-38 3533);
DISPLAY 0.680851 (-38 3533);
PAINT GREEN (-38 3533);
FORCEPROP 2 LAST CDS_LIB standard
J 0
(-100 3525);
DISPLAY INVISIBLE (-100 3525);
FORCEPROP 1 LAST BODY_TYPE PLUMBING
J 2
(-100 3575);
DISPLAY 0.872340 (-100 3575);
PAINT GREEN (-100 3575);
DISPLAY INVISIBLE (-100 3575);
FORCEPROP 1 LAST HDL_TAP TRUE
J 2
(-425 3400);
DISPLAY 0.872340 (-425 3400);
DISPLAY INVISIBLE (-425 3400);
FORCEPROP 1 LAST PATH I105
J 2
(-98 3525);
DISPLAY 0.872340 (-98 3525);
PAINT GREEN (-98 3525);
DISPLAY INVISIBLE (-98 3525);
FORCEADD TAP..1
R 2
(-100 3425);
FORCEPROP 3 LASTPIN (-50 3425) SIG_NAME UPI_CPU0_CPU1_P0P1_DP<13>
J 0
(-40 3435);
DISPLAY 0.659574 (-40 3435);
PAINT MONO (-40 3435);
DISPLAY INVISIBLE (-40 3435);
FORCEPROP 1 LASTPIN (-50 3425) BN 13
J 2
(-38 3433);
DISPLAY 0.680851 (-38 3433);
PAINT GREEN (-38 3433);
FORCEPROP 2 LAST CDS_LIB standard
J 0
(-100 3425);
DISPLAY INVISIBLE (-100 3425);
FORCEPROP 1 LAST BODY_TYPE PLUMBING
J 2
(-100 3475);
DISPLAY 0.872340 (-100 3475);
PAINT GREEN (-100 3475);
DISPLAY INVISIBLE (-100 3475);
FORCEPROP 1 LAST HDL_TAP TRUE
J 2
(-425 3300);
DISPLAY 0.872340 (-425 3300);
DISPLAY INVISIBLE (-425 3300);
FORCEPROP 1 LAST PATH I106
J 2
(-98 3425);
DISPLAY 0.872340 (-98 3425);
PAINT GREEN (-98 3425);
DISPLAY INVISIBLE (-98 3425);
FORCEADD TAP..1
R 2
(-100 3375);
FORCEPROP 3 LASTPIN (-50 3375) SIG_NAME UPI_CPU0_CPU1_P0P1_DP<12>
J 0
(-40 3385);
DISPLAY 0.659574 (-40 3385);
PAINT MONO (-40 3385);
DISPLAY INVISIBLE (-40 3385);
FORCEPROP 1 LASTPIN (-50 3375) BN 12
J 2
(-38 3383);
DISPLAY 0.680851 (-38 3383);
PAINT GREEN (-38 3383);
FORCEPROP 2 LAST CDS_LIB standard
J 0
(-100 3375);
DISPLAY INVISIBLE (-100 3375);
FORCEPROP 1 LAST BODY_TYPE PLUMBING
J 2
(-100 3425);
DISPLAY 0.872340 (-100 3425);
PAINT GREEN (-100 3425);
DISPLAY INVISIBLE (-100 3425);
FORCEPROP 1 LAST HDL_TAP TRUE
J 2
(-425 3250);
DISPLAY 0.872340 (-425 3250);
DISPLAY INVISIBLE (-425 3250);
FORCEPROP 1 LAST PATH I107
J 2
(-98 3375);
DISPLAY 0.872340 (-98 3375);
PAINT GREEN (-98 3375);
DISPLAY INVISIBLE (-98 3375);
FORCEADD TAP..1
R 2
(-100 2475);
FORCEPROP 3 LASTPIN (-50 2475) SIG_NAME UPI_CPU0_CPU1_P0P1_DN<19>
J 0
(-40 2485);
DISPLAY 0.659574 (-40 2485);
PAINT MONO (-40 2485);
DISPLAY INVISIBLE (-40 2485);
FORCEPROP 1 LASTPIN (-50 2475) BN 19
J 2
(-38 2483);
DISPLAY 0.680851 (-38 2483);
PAINT GREEN (-38 2483);
FORCEPROP 2 LAST CDS_LIB standard
J 0
(-100 2475);
PAINT MONO (-100 2475);
DISPLAY INVISIBLE (-100 2475);
FORCEPROP 1 LAST BODY_TYPE PLUMBING
J 2
(-100 2525);
DISPLAY 0.872340 (-100 2525);
PAINT GREEN (-100 2525);
DISPLAY INVISIBLE (-100 2525);
FORCEPROP 1 LAST HDL_TAP TRUE
J 2
(-425 2350);
DISPLAY 0.872340 (-425 2350);
DISPLAY INVISIBLE (-425 2350);
FORCEPROP 1 LAST PATH I108
J 2
(-98 2475);
DISPLAY 0.872340 (-98 2475);
PAINT GREEN (-98 2475);
DISPLAY INVISIBLE (-98 2475);
FORCEADD TAP..1
R 2
(-100 2425);
FORCEPROP 3 LASTPIN (-50 2425) SIG_NAME UPI_CPU0_CPU1_P0P1_DN<18>
J 0
(-40 2435);
DISPLAY 0.659574 (-40 2435);
PAINT MONO (-40 2435);
DISPLAY INVISIBLE (-40 2435);
FORCEPROP 1 LASTPIN (-50 2425) BN 18
J 2
(-38 2433);
DISPLAY 0.680851 (-38 2433);
PAINT GREEN (-38 2433);
FORCEPROP 2 LAST CDS_LIB standard
J 0
(-100 2425);
PAINT MONO (-100 2425);
DISPLAY INVISIBLE (-100 2425);
FORCEPROP 1 LAST BODY_TYPE PLUMBING
J 2
(-100 2475);
DISPLAY 0.872340 (-100 2475);
PAINT GREEN (-100 2475);
DISPLAY INVISIBLE (-100 2475);
FORCEPROP 1 LAST HDL_TAP TRUE
J 2
(-425 2300);
DISPLAY 0.872340 (-425 2300);
DISPLAY INVISIBLE (-425 2300);
FORCEPROP 1 LAST PATH I109
J 2
(-98 2425);
DISPLAY 0.872340 (-98 2425);
PAINT GREEN (-98 2425);
DISPLAY INVISIBLE (-98 2425);
FORCEADD TAP..1
R 2
(-100 2375);
FORCEPROP 3 LASTPIN (-50 2375) SIG_NAME UPI_CPU0_CPU1_P0P1_DN<17>
J 0
(-40 2385);
DISPLAY 0.659574 (-40 2385);
PAINT MONO (-40 2385);
DISPLAY INVISIBLE (-40 2385);
FORCEPROP 1 LASTPIN (-50 2375) BN 17
J 2
(-38 2383);
DISPLAY 0.680851 (-38 2383);
PAINT GREEN (-38 2383);
FORCEPROP 2 LAST CDS_LIB standard
J 0
(-100 2375);
PAINT MONO (-100 2375);
DISPLAY INVISIBLE (-100 2375);
FORCEPROP 1 LAST BODY_TYPE PLUMBING
J 2
(-100 2425);
DISPLAY 0.872340 (-100 2425);
PAINT GREEN (-100 2425);
DISPLAY INVISIBLE (-100 2425);
FORCEPROP 1 LAST HDL_TAP TRUE
J 2
(-425 2250);
DISPLAY 0.872340 (-425 2250);
DISPLAY INVISIBLE (-425 2250);
FORCEPROP 1 LAST PATH I110
J 2
(-98 2375);
DISPLAY 0.872340 (-98 2375);
PAINT GREEN (-98 2375);
DISPLAY INVISIBLE (-98 2375);
FORCEADD TAP..1
R 2
(-100 2325);
FORCEPROP 3 LASTPIN (-50 2325) SIG_NAME UPI_CPU0_CPU1_P0P1_DN<16>
J 0
(-40 2335);
DISPLAY 0.659574 (-40 2335);
PAINT MONO (-40 2335);
DISPLAY INVISIBLE (-40 2335);
FORCEPROP 1 LASTPIN (-50 2325) BN 16
J 2
(-38 2333);
DISPLAY 0.680851 (-38 2333);
PAINT GREEN (-38 2333);
FORCEPROP 2 LAST CDS_LIB standard
J 0
(-100 2325);
PAINT MONO (-100 2325);
DISPLAY INVISIBLE (-100 2325);
FORCEPROP 1 LAST BODY_TYPE PLUMBING
J 2
(-100 2375);
DISPLAY 0.872340 (-100 2375);
PAINT GREEN (-100 2375);
DISPLAY INVISIBLE (-100 2375);
FORCEPROP 1 LAST HDL_TAP TRUE
J 2
(-425 2200);
DISPLAY 0.872340 (-425 2200);
DISPLAY INVISIBLE (-425 2200);
FORCEPROP 1 LAST PATH I111
J 2
(-98 2325);
DISPLAY 0.872340 (-98 2325);
PAINT GREEN (-98 2325);
DISPLAY INVISIBLE (-98 2325);
FORCEADD TAP..1
R 2
(-100 2225);
FORCEPROP 3 LASTPIN (-50 2225) SIG_NAME UPI_CPU0_CPU1_P0P1_DN<14>
J 0
(-40 2235);
DISPLAY 0.659574 (-40 2235);
PAINT MONO (-40 2235);
DISPLAY INVISIBLE (-40 2235);
FORCEPROP 1 LASTPIN (-50 2225) BN 14
J 2
(-38 2233);
DISPLAY 0.680851 (-38 2233);
PAINT GREEN (-38 2233);
FORCEPROP 2 LAST CDS_LIB standard
J 0
(-100 2225);
DISPLAY INVISIBLE (-100 2225);
FORCEPROP 1 LAST BODY_TYPE PLUMBING
J 2
(-100 2275);
DISPLAY 0.872340 (-100 2275);
PAINT GREEN (-100 2275);
DISPLAY INVISIBLE (-100 2275);
FORCEPROP 1 LAST HDL_TAP TRUE
J 2
(-425 2100);
DISPLAY 0.872340 (-425 2100);
DISPLAY INVISIBLE (-425 2100);
FORCEPROP 1 LAST PATH I112
J 2
(-98 2225);
DISPLAY 0.872340 (-98 2225);
PAINT GREEN (-98 2225);
DISPLAY INVISIBLE (-98 2225);
FORCEADD TAP..1
R 2
(-100 2075);
FORCEPROP 3 LASTPIN (-50 2075) SIG_NAME UPI_CPU0_CPU1_P0P1_DN<11>
J 0
(-40 2085);
DISPLAY 0.659574 (-40 2085);
PAINT MONO (-40 2085);
DISPLAY INVISIBLE (-40 2085);
FORCEPROP 1 LASTPIN (-50 2075) BN 11
J 2
(-38 2083);
DISPLAY 0.680851 (-38 2083);
PAINT GREEN (-38 2083);
FORCEPROP 2 LAST CDS_LIB standard
J 0
(-100 2075);
DISPLAY INVISIBLE (-100 2075);
FORCEPROP 1 LAST BODY_TYPE PLUMBING
J 2
(-100 2125);
DISPLAY 0.872340 (-100 2125);
PAINT GREEN (-100 2125);
DISPLAY INVISIBLE (-100 2125);
FORCEPROP 1 LAST HDL_TAP TRUE
J 2
(-425 1950);
DISPLAY 0.872340 (-425 1950);
DISPLAY INVISIBLE (-425 1950);
FORCEPROP 1 LAST PATH I113
J 2
(-98 2075);
DISPLAY 0.872340 (-98 2075);
PAINT GREEN (-98 2075);
DISPLAY INVISIBLE (-98 2075);
FORCEADD TAP..1
R 2
(-100 2025);
FORCEPROP 3 LASTPIN (-50 2025) SIG_NAME UPI_CPU0_CPU1_P0P1_DN<10>
J 0
(-40 2035);
DISPLAY 0.659574 (-40 2035);
PAINT MONO (-40 2035);
DISPLAY INVISIBLE (-40 2035);
FORCEPROP 1 LASTPIN (-50 2025) BN 10
J 2
(-38 2033);
DISPLAY 0.680851 (-38 2033);
PAINT GREEN (-38 2033);
FORCEPROP 2 LAST CDS_LIB standard
J 0
(-100 2025);
DISPLAY INVISIBLE (-100 2025);
FORCEPROP 1 LAST BODY_TYPE PLUMBING
J 2
(-100 2075);
DISPLAY 0.872340 (-100 2075);
PAINT GREEN (-100 2075);
DISPLAY INVISIBLE (-100 2075);
FORCEPROP 1 LAST HDL_TAP TRUE
J 2
(-425 1900);
DISPLAY 0.872340 (-425 1900);
DISPLAY INVISIBLE (-425 1900);
FORCEPROP 1 LAST PATH I114
J 2
(-98 2025);
DISPLAY 0.872340 (-98 2025);
PAINT GREEN (-98 2025);
DISPLAY INVISIBLE (-98 2025);
FORCEADD TAP..1
R 2
(-100 1975);
FORCEPROP 3 LASTPIN (-50 1975) SIG_NAME UPI_CPU0_CPU1_P0P1_DN<9>
J 0
(-40 1985);
DISPLAY 0.659574 (-40 1985);
PAINT MONO (-40 1985);
DISPLAY INVISIBLE (-40 1985);
FORCEPROP 1 LASTPIN (-50 1975) BN 9
J 2
(-38 1983);
DISPLAY 0.680851 (-38 1983);
PAINT GREEN (-38 1983);
FORCEPROP 2 LAST CDS_LIB standard
J 0
(-100 1975);
DISPLAY INVISIBLE (-100 1975);
FORCEPROP 1 LAST BODY_TYPE PLUMBING
J 2
(-100 2025);
DISPLAY 0.872340 (-100 2025);
PAINT GREEN (-100 2025);
DISPLAY INVISIBLE (-100 2025);
FORCEPROP 1 LAST HDL_TAP TRUE
J 2
(-425 1850);
DISPLAY 0.872340 (-425 1850);
DISPLAY INVISIBLE (-425 1850);
FORCEPROP 1 LAST PATH I115
J 2
(-98 1975);
DISPLAY 0.872340 (-98 1975);
PAINT GREEN (-98 1975);
DISPLAY INVISIBLE (-98 1975);
FORCEADD TAP..1
R 2
(-100 1925);
FORCEPROP 3 LASTPIN (-50 1925) SIG_NAME UPI_CPU0_CPU1_P0P1_DN<8>
J 0
(-40 1935);
DISPLAY 0.659574 (-40 1935);
PAINT MONO (-40 1935);
DISPLAY INVISIBLE (-40 1935);
FORCEPROP 1 LASTPIN (-50 1925) BN 8
J 2
(-38 1933);
DISPLAY 0.680851 (-38 1933);
PAINT GREEN (-38 1933);
FORCEPROP 2 LAST CDS_LIB standard
J 0
(-100 1925);
DISPLAY INVISIBLE (-100 1925);
FORCEPROP 1 LAST BODY_TYPE PLUMBING
J 2
(-100 1975);
DISPLAY 0.872340 (-100 1975);
PAINT GREEN (-100 1975);
DISPLAY INVISIBLE (-100 1975);
FORCEPROP 1 LAST HDL_TAP TRUE
J 2
(-425 1800);
DISPLAY 0.872340 (-425 1800);
DISPLAY INVISIBLE (-425 1800);
FORCEPROP 1 LAST PATH I116
J 2
(-98 1925);
DISPLAY 0.872340 (-98 1925);
PAINT GREEN (-98 1925);
DISPLAY INVISIBLE (-98 1925);
FORCEADD TAP..1
R 2
(-100 1875);
FORCEPROP 3 LASTPIN (-50 1875) SIG_NAME UPI_CPU0_CPU1_P0P1_DN<7>
J 0
(-40 1885);
DISPLAY 0.659574 (-40 1885);
PAINT MONO (-40 1885);
DISPLAY INVISIBLE (-40 1885);
FORCEPROP 1 LASTPIN (-50 1875) BN 7
J 2
(-38 1883);
DISPLAY 0.680851 (-38 1883);
PAINT GREEN (-38 1883);
FORCEPROP 2 LAST CDS_LIB standard
J 0
(-100 1875);
DISPLAY INVISIBLE (-100 1875);
FORCEPROP 1 LAST BODY_TYPE PLUMBING
J 2
(-100 1925);
DISPLAY 0.872340 (-100 1925);
PAINT GREEN (-100 1925);
DISPLAY INVISIBLE (-100 1925);
FORCEPROP 1 LAST HDL_TAP TRUE
J 2
(-425 1750);
DISPLAY 0.872340 (-425 1750);
DISPLAY INVISIBLE (-425 1750);
FORCEPROP 1 LAST PATH I117
J 2
(-98 1875);
DISPLAY 0.872340 (-98 1875);
PAINT GREEN (-98 1875);
DISPLAY INVISIBLE (-98 1875);
FORCEADD TAP..1
R 2
(-100 1825);
FORCEPROP 3 LASTPIN (-50 1825) SIG_NAME UPI_CPU0_CPU1_P0P1_DN<6>
J 0
(-40 1835);
DISPLAY 0.659574 (-40 1835);
PAINT MONO (-40 1835);
DISPLAY INVISIBLE (-40 1835);
FORCEPROP 1 LASTPIN (-50 1825) BN 6
J 2
(-38 1833);
DISPLAY 0.680851 (-38 1833);
PAINT GREEN (-38 1833);
FORCEPROP 2 LAST CDS_LIB standard
J 0
(-100 1825);
DISPLAY INVISIBLE (-100 1825);
FORCEPROP 1 LAST BODY_TYPE PLUMBING
J 2
(-100 1875);
DISPLAY 0.872340 (-100 1875);
PAINT GREEN (-100 1875);
DISPLAY INVISIBLE (-100 1875);
FORCEPROP 1 LAST HDL_TAP TRUE
J 2
(-425 1700);
DISPLAY 0.872340 (-425 1700);
DISPLAY INVISIBLE (-425 1700);
FORCEPROP 1 LAST PATH I118
J 2
(-98 1825);
DISPLAY 0.872340 (-98 1825);
PAINT GREEN (-98 1825);
DISPLAY INVISIBLE (-98 1825);
FORCEADD TAP..1
R 2
(-100 1775);
FORCEPROP 3 LASTPIN (-50 1775) SIG_NAME UPI_CPU0_CPU1_P0P1_DN<5>
J 0
(-40 1785);
DISPLAY 0.659574 (-40 1785);
PAINT MONO (-40 1785);
DISPLAY INVISIBLE (-40 1785);
FORCEPROP 1 LASTPIN (-50 1775) BN 5
J 2
(-38 1783);
DISPLAY 0.680851 (-38 1783);
PAINT GREEN (-38 1783);
FORCEPROP 2 LAST CDS_LIB standard
J 0
(-100 1775);
DISPLAY INVISIBLE (-100 1775);
FORCEPROP 1 LAST BODY_TYPE PLUMBING
J 2
(-100 1825);
DISPLAY 0.872340 (-100 1825);
PAINT GREEN (-100 1825);
DISPLAY INVISIBLE (-100 1825);
FORCEPROP 1 LAST HDL_TAP TRUE
J 2
(-425 1650);
DISPLAY 0.872340 (-425 1650);
DISPLAY INVISIBLE (-425 1650);
FORCEPROP 1 LAST PATH I119
J 2
(-98 1775);
DISPLAY 0.872340 (-98 1775);
PAINT GREEN (-98 1775);
DISPLAY INVISIBLE (-98 1775);
FORCEADD TAP..1
R 2
(-100 1725);
FORCEPROP 3 LASTPIN (-50 1725) SIG_NAME UPI_CPU0_CPU1_P0P1_DN<4>
J 0
(-40 1735);
DISPLAY 0.659574 (-40 1735);
PAINT MONO (-40 1735);
DISPLAY INVISIBLE (-40 1735);
FORCEPROP 1 LASTPIN (-50 1725) BN 4
J 2
(-38 1733);
DISPLAY 0.680851 (-38 1733);
PAINT GREEN (-38 1733);
FORCEPROP 2 LAST CDS_LIB standard
J 0
(-100 1725);
DISPLAY INVISIBLE (-100 1725);
FORCEPROP 1 LAST BODY_TYPE PLUMBING
J 2
(-100 1775);
DISPLAY 0.872340 (-100 1775);
PAINT GREEN (-100 1775);
DISPLAY INVISIBLE (-100 1775);
FORCEPROP 1 LAST HDL_TAP TRUE
J 2
(-425 1600);
DISPLAY 0.872340 (-425 1600);
DISPLAY INVISIBLE (-425 1600);
FORCEPROP 1 LAST PATH I120
J 2
(-98 1725);
DISPLAY 0.872340 (-98 1725);
PAINT GREEN (-98 1725);
DISPLAY INVISIBLE (-98 1725);
FORCEADD TAP..1
R 2
(-100 1675);
FORCEPROP 3 LASTPIN (-50 1675) SIG_NAME UPI_CPU0_CPU1_P0P1_DN<3>
J 0
(-40 1685);
DISPLAY 0.659574 (-40 1685);
PAINT MONO (-40 1685);
DISPLAY INVISIBLE (-40 1685);
FORCEPROP 1 LASTPIN (-50 1675) BN 3
J 2
(-38 1683);
DISPLAY 0.680851 (-38 1683);
PAINT GREEN (-38 1683);
FORCEPROP 2 LAST CDS_LIB standard
J 0
(-100 1675);
DISPLAY INVISIBLE (-100 1675);
FORCEPROP 1 LAST BODY_TYPE PLUMBING
J 2
(-100 1725);
DISPLAY 0.872340 (-100 1725);
PAINT GREEN (-100 1725);
DISPLAY INVISIBLE (-100 1725);
FORCEPROP 1 LAST HDL_TAP TRUE
J 2
(-425 1550);
DISPLAY 0.872340 (-425 1550);
DISPLAY INVISIBLE (-425 1550);
FORCEPROP 1 LAST PATH I121
J 2
(-98 1675);
DISPLAY 0.872340 (-98 1675);
PAINT GREEN (-98 1675);
DISPLAY INVISIBLE (-98 1675);
FORCEADD TAP..1
R 2
(-100 1625);
FORCEPROP 3 LASTPIN (-50 1625) SIG_NAME UPI_CPU0_CPU1_P0P1_DN<2>
J 0
(-40 1635);
DISPLAY 0.659574 (-40 1635);
PAINT MONO (-40 1635);
DISPLAY INVISIBLE (-40 1635);
FORCEPROP 1 LASTPIN (-50 1625) BN 2
J 2
(-38 1633);
DISPLAY 0.680851 (-38 1633);
PAINT GREEN (-38 1633);
FORCEPROP 2 LAST CDS_LIB standard
J 0
(-100 1625);
DISPLAY INVISIBLE (-100 1625);
FORCEPROP 1 LAST BODY_TYPE PLUMBING
J 2
(-100 1675);
DISPLAY 0.872340 (-100 1675);
PAINT GREEN (-100 1675);
DISPLAY INVISIBLE (-100 1675);
FORCEPROP 1 LAST HDL_TAP TRUE
J 2
(-425 1500);
DISPLAY 0.872340 (-425 1500);
DISPLAY INVISIBLE (-425 1500);
FORCEPROP 1 LAST PATH I122
J 2
(-98 1625);
DISPLAY 0.872340 (-98 1625);
PAINT GREEN (-98 1625);
DISPLAY INVISIBLE (-98 1625);
FORCEADD TAP..1
R 2
(-100 1575);
FORCEPROP 3 LASTPIN (-50 1575) SIG_NAME UPI_CPU0_CPU1_P0P1_DN<1>
J 0
(-40 1585);
DISPLAY 0.659574 (-40 1585);
PAINT MONO (-40 1585);
DISPLAY INVISIBLE (-40 1585);
FORCEPROP 1 LASTPIN (-50 1575) BN 1
J 2
(-38 1583);
DISPLAY 0.680851 (-38 1583);
PAINT GREEN (-38 1583);
FORCEPROP 2 LAST CDS_LIB standard
J 0
(-100 1575);
DISPLAY INVISIBLE (-100 1575);
FORCEPROP 1 LAST BODY_TYPE PLUMBING
J 2
(-100 1625);
DISPLAY 0.872340 (-100 1625);
PAINT GREEN (-100 1625);
DISPLAY INVISIBLE (-100 1625);
FORCEPROP 1 LAST HDL_TAP TRUE
J 2
(-425 1450);
DISPLAY 0.872340 (-425 1450);
DISPLAY INVISIBLE (-425 1450);
FORCEPROP 1 LAST PATH I123
J 2
(-98 1575);
DISPLAY 0.872340 (-98 1575);
PAINT GREEN (-98 1575);
DISPLAY INVISIBLE (-98 1575);
FORCEADD TAP..1
R 2
(-100 1525);
FORCEPROP 3 LASTPIN (-50 1525) SIG_NAME UPI_CPU0_CPU1_P0P1_DN<0>
J 0
(-40 1535);
DISPLAY 0.659574 (-40 1535);
PAINT MONO (-40 1535);
DISPLAY INVISIBLE (-40 1535);
FORCEPROP 1 LASTPIN (-50 1525) BN 0
J 2
(-38 1533);
DISPLAY 0.680851 (-38 1533);
PAINT GREEN (-38 1533);
FORCEPROP 2 LAST CDS_LIB standard
J 0
(-100 1525);
DISPLAY INVISIBLE (-100 1525);
FORCEPROP 1 LAST BODY_TYPE PLUMBING
J 2
(-100 1575);
DISPLAY 0.872340 (-100 1575);
PAINT GREEN (-100 1575);
DISPLAY INVISIBLE (-100 1575);
FORCEPROP 1 LAST HDL_TAP TRUE
J 2
(-425 1400);
DISPLAY 0.872340 (-425 1400);
DISPLAY INVISIBLE (-425 1400);
FORCEPROP 1 LAST PATH I124
J 2
(-98 1525);
DISPLAY 0.872340 (-98 1525);
PAINT GREEN (-98 1525);
DISPLAY INVISIBLE (-98 1525);
FORCEADD TAP..1
R 2
(-100 2675);
FORCEPROP 3 LASTPIN (-50 2675) SIG_NAME UPI_CPU0_CPU1_P0P1_DN<23>
J 0
(-40 2685);
DISPLAY 0.659574 (-40 2685);
PAINT MONO (-40 2685);
DISPLAY INVISIBLE (-40 2685);
FORCEPROP 1 LASTPIN (-50 2675) BN 23
J 2
(-38 2683);
DISPLAY 0.680851 (-38 2683);
PAINT GREEN (-38 2683);
FORCEPROP 2 LAST CDS_LIB standard
J 0
(-100 2675);
PAINT MONO (-100 2675);
DISPLAY INVISIBLE (-100 2675);
FORCEPROP 1 LAST BODY_TYPE PLUMBING
J 2
(-100 2725);
DISPLAY 0.872340 (-100 2725);
PAINT GREEN (-100 2725);
DISPLAY INVISIBLE (-100 2725);
FORCEPROP 1 LAST HDL_TAP TRUE
J 2
(-425 2550);
DISPLAY 0.872340 (-425 2550);
DISPLAY INVISIBLE (-425 2550);
FORCEPROP 1 LAST PATH I125
J 2
(-98 2675);
DISPLAY 0.872340 (-98 2675);
PAINT GREEN (-98 2675);
DISPLAY INVISIBLE (-98 2675);
FORCEADD OFFPAGE..1
(-1350 2725);
FORCEPROP 2 LAST $XR0 32 
J 0
(-1571 2725);
DISPLAY 0.638298 (-1571 2725);
PAINT MONO (-1571 2725);
FORCEPROP 2 LAST CDS_LIB standard
J 0
(-1350 2725);
PAINT MONO (-1350 2725);
DISPLAY INVISIBLE (-1350 2725);
FORCEPROP 1 LAST OFFPAGE TRUE
J 0
(-1025 2600);
DISPLAY 0.872340 (-1025 2600);
DISPLAY INVISIBLE (-1025 2600);
FORCEPROP 1 LAST COMMENT_BODY TRUE
J 0
(-1225 2625);
DISPLAY 0.872340 (-1225 2625);
PAINT GREEN (-1225 2625);
DISPLAY INVISIBLE (-1225 2625);
FORCEPROP 2 LAST PATH I126
J 0
(-1600 2775);
DISPLAY 1.021277 (-1600 2775);
DISPLAY INVISIBLE (-1600 2775);
FORCEADD TAP..1
R 2
(-100 2125);
FORCEPROP 3 LASTPIN (-50 2125) SIG_NAME UPI_CPU0_CPU1_P0P1_DN<12>
J 0
(-40 2135);
DISPLAY 0.659574 (-40 2135);
PAINT MONO (-40 2135);
DISPLAY INVISIBLE (-40 2135);
FORCEPROP 1 LASTPIN (-50 2125) BN 12
J 2
(-38 2133);
DISPLAY 0.680851 (-38 2133);
PAINT GREEN (-38 2133);
FORCEPROP 2 LAST CDS_LIB standard
J 0
(-100 2125);
DISPLAY INVISIBLE (-100 2125);
FORCEPROP 1 LAST BODY_TYPE PLUMBING
J 2
(-100 2175);
DISPLAY 0.872340 (-100 2175);
PAINT GREEN (-100 2175);
DISPLAY INVISIBLE (-100 2175);
FORCEPROP 1 LAST HDL_TAP TRUE
J 2
(-425 2000);
DISPLAY 0.872340 (-425 2000);
DISPLAY INVISIBLE (-425 2000);
FORCEPROP 1 LAST PATH I15
J 2
(-98 2125);
DISPLAY 0.872340 (-98 2125);
PAINT GREEN (-98 2125);
DISPLAY INVISIBLE (-98 2125);
FORCEADD TAP..1
R 2
(-100 2175);
FORCEPROP 3 LASTPIN (-50 2175) SIG_NAME UPI_CPU0_CPU1_P0P1_DN<13>
J 0
(-40 2185);
DISPLAY 0.659574 (-40 2185);
PAINT MONO (-40 2185);
DISPLAY INVISIBLE (-40 2185);
FORCEPROP 1 LASTPIN (-50 2175) BN 13
J 2
(-38 2183);
DISPLAY 0.680851 (-38 2183);
PAINT GREEN (-38 2183);
FORCEPROP 2 LAST CDS_LIB standard
J 0
(-100 2175);
DISPLAY INVISIBLE (-100 2175);
FORCEPROP 1 LAST BODY_TYPE PLUMBING
J 2
(-100 2225);
DISPLAY 0.872340 (-100 2225);
PAINT GREEN (-100 2225);
DISPLAY INVISIBLE (-100 2225);
FORCEPROP 1 LAST HDL_TAP TRUE
J 2
(-425 2050);
DISPLAY 0.872340 (-425 2050);
DISPLAY INVISIBLE (-425 2050);
FORCEPROP 1 LAST PATH I16
J 2
(-98 2175);
DISPLAY 0.872340 (-98 2175);
PAINT GREEN (-98 2175);
DISPLAY INVISIBLE (-98 2175);
FORCEADD TAP..1
R 2
(-100 2275);
FORCEPROP 3 LASTPIN (-50 2275) SIG_NAME UPI_CPU0_CPU1_P0P1_DN<15>
J 0
(-40 2285);
DISPLAY 0.659574 (-40 2285);
PAINT MONO (-40 2285);
DISPLAY INVISIBLE (-40 2285);
FORCEPROP 1 LASTPIN (-50 2275) BN 15
J 2
(-38 2283);
DISPLAY 0.680851 (-38 2283);
PAINT GREEN (-38 2283);
FORCEPROP 2 LAST CDS_LIB standard
J 0
(-100 2275);
DISPLAY INVISIBLE (-100 2275);
FORCEPROP 1 LAST BODY_TYPE PLUMBING
J 2
(-100 2325);
DISPLAY 0.872340 (-100 2325);
PAINT GREEN (-100 2325);
DISPLAY INVISIBLE (-100 2325);
FORCEPROP 1 LAST HDL_TAP TRUE
J 2
(-425 2150);
DISPLAY 0.872340 (-425 2150);
DISPLAY INVISIBLE (-425 2150);
FORCEPROP 1 LAST PATH I19
J 2
(-98 2275);
DISPLAY 0.872340 (-98 2275);
PAINT GREEN (-98 2275);
DISPLAY INVISIBLE (-98 2275);
FORCEADD SOCKET4677_AZIF0045P001C01CS..23
(1600 2725);
FORCEPROP 1 LAST PART_NUMBER DGA^7000023
J 0
(550 4175);
DISPLAY 0.723404 (550 4175);
PAINT GREEN (550 4175);
DISPLAY INVISIBLE (550 4175);
FORCEPROP 2 LAST VALUE SOCKET4677_AZIF0045-P001C01CS
J 0
(550 4300);
DISPLAY 1.021277 (550 4300);
FORCEPROP 1 LAST MATERIAL IO
J 0
(550 4100);
DISPLAY 0.723404 (550 4100);
PAINT GREEN (550 4100);
FORCEPROP 2 LAST PART_TYPE SMLF
J 0
(550 4350);
DISPLAY 1.021277 (550 4350);
FORCEPROP 1 LAST $LOCATION U1
J 0
(550 4250);
DISPLAY 0.723404 (550 4250);
PAINT GREEN (550 4250);
FORCEPROP 0 LASTPIN (400 1525) $PN EH2
J 2
(390 1535);
DISPLAY 0.680851 (390 1535);
PAINT MONO (390 1535);
FORCEPROP 0 LASTPIN (400 1575) $PN EE3
J 2
(390 1585);
DISPLAY 0.680851 (390 1585);
PAINT MONO (390 1585);
FORCEPROP 0 LASTPIN (400 1625) $PN ED2
J 2
(390 1635);
DISPLAY 0.680851 (390 1635);
PAINT MONO (390 1635);
FORCEPROP 0 LASTPIN (400 1675) $PN EA1
J 2
(390 1685);
DISPLAY 0.680851 (390 1685);
PAINT MONO (390 1685);
FORCEPROP 0 LASTPIN (400 1725) $PN DY2
J 2
(390 1735);
DISPLAY 0.680851 (390 1735);
PAINT MONO (390 1735);
FORCEPROP 0 LASTPIN (400 1775) $PN DU1
J 2
(390 1785);
DISPLAY 0.680851 (390 1785);
PAINT MONO (390 1785);
FORCEPROP 0 LASTPIN (400 1825) $PN DT2
J 2
(390 1835);
DISPLAY 0.680851 (390 1835);
PAINT MONO (390 1835);
FORCEPROP 0 LASTPIN (400 1875) $PN DN1
J 2
(390 1885);
DISPLAY 0.680851 (390 1885);
PAINT MONO (390 1885);
FORCEPROP 0 LASTPIN (400 1925) $PN DL3
J 2
(390 1935);
DISPLAY 0.680851 (390 1935);
PAINT MONO (390 1935);
FORCEPROP 0 LASTPIN (400 1975) $PN DJ1
J 2
(390 1985);
DISPLAY 0.680851 (390 1985);
PAINT MONO (390 1985);
FORCEPROP 0 LASTPIN (400 2025) $PN DG3
J 2
(390 2035);
DISPLAY 0.680851 (390 2035);
PAINT MONO (390 2035);
FORCEPROP 0 LASTPIN (400 2075) $PN DE1
J 2
(390 2085);
DISPLAY 0.680851 (390 2085);
PAINT MONO (390 2085);
FORCEPROP 0 LASTPIN (400 2125) $PN DD2
J 2
(390 2135);
DISPLAY 0.680851 (390 2135);
PAINT MONO (390 2135);
FORCEPROP 0 LASTPIN (400 2175) $PN DB2
J 2
(390 2185);
DISPLAY 0.680851 (390 2185);
PAINT MONO (390 2185);
FORCEPROP 0 LASTPIN (400 2225) $PN CY2
J 2
(390 2235);
DISPLAY 0.680851 (390 2235);
PAINT MONO (390 2235);
FORCEPROP 0 LASTPIN (400 2275) $PN CV2
J 2
(390 2285);
DISPLAY 0.680851 (390 2285);
PAINT MONO (390 2285);
FORCEPROP 0 LASTPIN (400 2325) $PN CR3
J 2
(390 2335);
DISPLAY 0.680851 (390 2335);
PAINT MONO (390 2335);
FORCEPROP 0 LASTPIN (400 2375) $PN CN1
J 2
(390 2385);
DISPLAY 0.680851 (390 2385);
PAINT MONO (390 2385);
FORCEPROP 0 LASTPIN (400 2425) $PN CL3
J 2
(390 2435);
DISPLAY 0.680851 (390 2435);
PAINT MONO (390 2435);
FORCEPROP 0 LASTPIN (400 2475) $PN CJ1
J 2
(390 2485);
DISPLAY 0.680851 (390 2485);
PAINT MONO (390 2485);
FORCEPROP 0 LASTPIN (400 2525) $PN CH2
J 2
(390 2535);
DISPLAY 0.680851 (390 2535);
PAINT MONO (390 2535);
FORCEPROP 0 LASTPIN (400 2575) $PN CF2
J 2
(390 2585);
DISPLAY 0.680851 (390 2585);
PAINT MONO (390 2585);
FORCEPROP 0 LASTPIN (400 2625) $PN CD2
J 2
(390 2635);
DISPLAY 0.680851 (390 2635);
PAINT MONO (390 2635);
FORCEPROP 0 LASTPIN (400 2675) $PN CB2
J 2
(390 2685);
DISPLAY 0.680851 (390 2685);
PAINT MONO (390 2685);
FORCEPROP 0 LASTPIN (400 2775) $PN EJ3
J 2
(390 2785);
DISPLAY 0.680851 (390 2785);
PAINT MONO (390 2785);
FORCEPROP 0 LASTPIN (400 2825) $PN EG3
J 2
(390 2835);
DISPLAY 0.680851 (390 2835);
PAINT MONO (390 2835);
FORCEPROP 0 LASTPIN (400 2875) $PN EC3
J 2
(390 2885);
DISPLAY 0.680851 (390 2885);
PAINT MONO (390 2885);
FORCEPROP 0 LASTPIN (400 2925) $PN EB2
J 2
(390 2935);
DISPLAY 0.680851 (390 2935);
PAINT MONO (390 2935);
FORCEPROP 0 LASTPIN (400 2975) $PN DW3
J 2
(390 2985);
DISPLAY 0.680851 (390 2985);
PAINT MONO (390 2985);
FORCEPROP 0 LASTPIN (400 3025) $PN DV2
J 2
(390 3035);
DISPLAY 0.680851 (390 3035);
PAINT MONO (390 3035);
FORCEPROP 0 LASTPIN (400 3075) $PN DR3
J 2
(390 3085);
DISPLAY 0.680851 (390 3085);
PAINT MONO (390 3085);
FORCEPROP 0 LASTPIN (400 3125) $PN DP2
J 2
(390 3135);
DISPLAY 0.680851 (390 3135);
PAINT MONO (390 3135);
FORCEPROP 0 LASTPIN (400 3175) $PN DM2
J 2
(390 3185);
DISPLAY 0.680851 (390 3185);
PAINT MONO (390 3185);
FORCEPROP 0 LASTPIN (400 3225) $PN DK2
J 2
(390 3235);
DISPLAY 0.680851 (390 3235);
PAINT MONO (390 3235);
FORCEPROP 0 LASTPIN (400 3275) $PN DH2
J 2
(390 3285);
DISPLAY 0.680851 (390 3285);
PAINT MONO (390 3285);
FORCEPROP 0 LASTPIN (400 3325) $PN DF2
J 2
(390 3335);
DISPLAY 0.680851 (390 3335);
PAINT MONO (390 3335);
FORCEPROP 0 LASTPIN (400 3375) $PN DC3
J 2
(390 3385);
DISPLAY 0.680851 (390 3385);
PAINT MONO (390 3385);
FORCEPROP 0 LASTPIN (400 3425) $PN DA1
J 2
(390 3435);
DISPLAY 0.680851 (390 3435);
PAINT MONO (390 3435);
FORCEPROP 0 LASTPIN (400 3475) $PN CW3
J 2
(390 3485);
DISPLAY 0.680851 (390 3485);
PAINT MONO (390 3485);
FORCEPROP 0 LASTPIN (400 3525) $PN CU1
J 2
(390 3535);
DISPLAY 0.680851 (390 3535);
PAINT MONO (390 3535);
FORCEPROP 0 LASTPIN (400 3575) $PN CT2
J 2
(390 3585);
DISPLAY 0.680851 (390 3585);
PAINT MONO (390 3585);
FORCEPROP 0 LASTPIN (400 3625) $PN CP2
J 2
(390 3635);
DISPLAY 0.680851 (390 3635);
PAINT MONO (390 3635);
FORCEPROP 0 LASTPIN (400 3675) $PN CM2
J 2
(390 3685);
DISPLAY 0.680851 (390 3685);
PAINT MONO (390 3685);
FORCEPROP 0 LASTPIN (400 3725) $PN CK2
J 2
(390 3735);
DISPLAY 0.680851 (390 3735);
PAINT MONO (390 3735);
FORCEPROP 0 LASTPIN (400 3775) $PN CG3
J 2
(390 3785);
DISPLAY 0.680851 (390 3785);
PAINT MONO (390 3785);
FORCEPROP 0 LASTPIN (400 3825) $PN CE1
J 2
(390 3835);
DISPLAY 0.680851 (390 3835);
PAINT MONO (390 3835);
FORCEPROP 0 LASTPIN (400 3875) $PN CC3
J 2
(390 3885);
DISPLAY 0.680851 (390 3885);
PAINT MONO (390 3885);
FORCEPROP 0 LASTPIN (400 3925) $PN BY2
J 2
(390 3935);
DISPLAY 0.680851 (390 3935);
PAINT MONO (390 3935);
FORCEPROP 0 LASTPIN (2800 1525) $PN EF6
J 0
(2810 1535);
DISPLAY 0.680851 (2810 1535);
PAINT MONO (2810 1535);
FORCEPROP 0 LASTPIN (2800 1575) $PN EC7
J 0
(2810 1585);
DISPLAY 0.680851 (2810 1585);
PAINT MONO (2810 1585);
FORCEPROP 0 LASTPIN (2800 1625) $PN EB6
J 0
(2810 1635);
DISPLAY 0.680851 (2810 1635);
PAINT MONO (2810 1635);
FORCEPROP 0 LASTPIN (2800 1675) $PN DY6
J 0
(2810 1685);
DISPLAY 0.680851 (2810 1685);
PAINT MONO (2810 1685);
FORCEPROP 0 LASTPIN (2800 1725) $PN DV6
J 0
(2810 1735);
DISPLAY 0.680851 (2810 1735);
PAINT MONO (2810 1735);
FORCEPROP 0 LASTPIN (2800 1775) $PN DT6
J 0
(2810 1785);
DISPLAY 0.680851 (2810 1785);
PAINT MONO (2810 1785);
FORCEPROP 0 LASTPIN (2800 1825) $PN DP6
J 0
(2810 1835);
DISPLAY 0.680851 (2810 1835);
PAINT MONO (2810 1835);
FORCEPROP 0 LASTPIN (2800 1875) $PN DL7
J 0
(2810 1885);
DISPLAY 0.680851 (2810 1885);
PAINT MONO (2810 1885);
FORCEPROP 0 LASTPIN (2800 1925) $PN DK6
J 0
(2810 1935);
DISPLAY 0.680851 (2810 1935);
PAINT MONO (2810 1935);
FORCEPROP 0 LASTPIN (2800 1975) $PN DH6
J 0
(2810 1985);
DISPLAY 0.680851 (2810 1985);
PAINT MONO (2810 1985);
FORCEPROP 0 LASTPIN (2800 2025) $PN DE5
J 0
(2810 2035);
DISPLAY 0.680851 (2810 2035);
PAINT MONO (2810 2035);
FORCEPROP 0 LASTPIN (2800 2075) $PN DD6
J 0
(2810 2085);
DISPLAY 0.680851 (2810 2085);
PAINT MONO (2810 2085);
FORCEPROP 0 LASTPIN (2800 2125) $PN DA5
J 0
(2810 2135);
DISPLAY 0.680851 (2810 2135);
PAINT MONO (2810 2135);
FORCEPROP 0 LASTPIN (2800 2175) $PN CY6
J 0
(2810 2185);
DISPLAY 0.680851 (2810 2185);
PAINT MONO (2810 2185);
FORCEPROP 0 LASTPIN (2800 2225) $PN CU5
J 0
(2810 2235);
DISPLAY 0.680851 (2810 2235);
PAINT MONO (2810 2235);
FORCEPROP 0 LASTPIN (2800 2275) $PN CT6
J 0
(2810 2285);
DISPLAY 0.680851 (2810 2285);
PAINT MONO (2810 2285);
FORCEPROP 0 LASTPIN (2800 2325) $PN CN5
J 0
(2810 2335);
DISPLAY 0.680851 (2810 2335);
PAINT MONO (2810 2335);
FORCEPROP 0 LASTPIN (2800 2375) $PN CM6
J 0
(2810 2385);
DISPLAY 0.680851 (2810 2385);
PAINT MONO (2810 2385);
FORCEPROP 0 LASTPIN (2800 2425) $PN CJ5
J 0
(2810 2435);
DISPLAY 0.680851 (2810 2435);
PAINT MONO (2810 2435);
FORCEPROP 0 LASTPIN (2800 2475) $PN CH6
J 0
(2810 2485);
DISPLAY 0.680851 (2810 2485);
PAINT MONO (2810 2485);
FORCEPROP 0 LASTPIN (2800 2525) $PN CE5
J 0
(2810 2535);
DISPLAY 0.680851 (2810 2535);
PAINT MONO (2810 2535);
FORCEPROP 0 LASTPIN (2800 2575) $PN CD6
J 0
(2810 2585);
DISPLAY 0.680851 (2810 2585);
PAINT MONO (2810 2585);
FORCEPROP 0 LASTPIN (2800 2625) $PN CA5
J 0
(2810 2635);
DISPLAY 0.680851 (2810 2635);
PAINT MONO (2810 2635);
FORCEPROP 0 LASTPIN (2800 2675) $PN BY6
J 0
(2810 2685);
DISPLAY 0.680851 (2810 2685);
PAINT MONO (2810 2685);
FORCEPROP 0 LASTPIN (2800 2775) $PN EE5
J 0
(2810 2785);
DISPLAY 0.680851 (2810 2785);
PAINT MONO (2810 2785);
FORCEPROP 0 LASTPIN (2800 2825) $PN ED6
J 0
(2810 2835);
DISPLAY 0.680851 (2810 2835);
PAINT MONO (2810 2835);
FORCEPROP 0 LASTPIN (2800 2875) $PN EA5
J 0
(2810 2885);
DISPLAY 0.680851 (2810 2885);
PAINT MONO (2810 2885);
FORCEPROP 0 LASTPIN (2800 2925) $PN DW7
J 0
(2810 2935);
DISPLAY 0.680851 (2810 2935);
PAINT MONO (2810 2935);
FORCEPROP 0 LASTPIN (2800 2975) $PN DU5
J 0
(2810 2985);
DISPLAY 0.680851 (2810 2985);
PAINT MONO (2810 2985);
FORCEPROP 0 LASTPIN (2800 3025) $PN DR7
J 0
(2810 3035);
DISPLAY 0.680851 (2810 3035);
PAINT MONO (2810 3035);
FORCEPROP 0 LASTPIN (2800 3075) $PN DN5
J 0
(2810 3085);
DISPLAY 0.680851 (2810 3085);
PAINT MONO (2810 3085);
FORCEPROP 0 LASTPIN (2800 3125) $PN DM6
J 0
(2810 3135);
DISPLAY 0.680851 (2810 3135);
PAINT MONO (2810 3135);
FORCEPROP 0 LASTPIN (2800 3175) $PN DJ5
J 0
(2810 3185);
DISPLAY 0.680851 (2810 3185);
PAINT MONO (2810 3185);
FORCEPROP 0 LASTPIN (2800 3225) $PN DG7
J 0
(2810 3235);
DISPLAY 0.680851 (2810 3235);
PAINT MONO (2810 3235);
FORCEPROP 0 LASTPIN (2800 3275) $PN DF6
J 0
(2810 3285);
DISPLAY 0.680851 (2810 3285);
PAINT MONO (2810 3285);
FORCEPROP 0 LASTPIN (2800 3325) $PN DC7
J 0
(2810 3335);
DISPLAY 0.680851 (2810 3335);
PAINT MONO (2810 3335);
FORCEPROP 0 LASTPIN (2800 3375) $PN DB6
J 0
(2810 3385);
DISPLAY 0.680851 (2810 3385);
PAINT MONO (2810 3385);
FORCEPROP 0 LASTPIN (2800 3425) $PN CW7
J 0
(2810 3435);
DISPLAY 0.680851 (2810 3435);
PAINT MONO (2810 3435);
FORCEPROP 0 LASTPIN (2800 3475) $PN CV6
J 0
(2810 3485);
DISPLAY 0.680851 (2810 3485);
PAINT MONO (2810 3485);
FORCEPROP 0 LASTPIN (2800 3525) $PN CR7
J 0
(2810 3535);
DISPLAY 0.680851 (2810 3535);
PAINT MONO (2810 3535);
FORCEPROP 0 LASTPIN (2800 3575) $PN CP6
J 0
(2810 3585);
DISPLAY 0.680851 (2810 3585);
PAINT MONO (2810 3585);
FORCEPROP 0 LASTPIN (2800 3625) $PN CL7
J 0
(2810 3635);
DISPLAY 0.680851 (2810 3635);
PAINT MONO (2810 3635);
FORCEPROP 0 LASTPIN (2800 3675) $PN CK6
J 0
(2810 3685);
DISPLAY 0.680851 (2810 3685);
PAINT MONO (2810 3685);
FORCEPROP 0 LASTPIN (2800 3725) $PN CG7
J 0
(2810 3735);
DISPLAY 0.680851 (2810 3735);
PAINT MONO (2810 3735);
FORCEPROP 0 LASTPIN (2800 3775) $PN CF6
J 0
(2810 3785);
DISPLAY 0.680851 (2810 3785);
PAINT MONO (2810 3785);
FORCEPROP 0 LASTPIN (2800 3825) $PN CC7
J 0
(2810 3835);
DISPLAY 0.680851 (2810 3835);
PAINT MONO (2810 3835);
FORCEPROP 0 LASTPIN (2800 3875) $PN CB6
J 0
(2810 3885);
DISPLAY 0.680851 (2810 3885);
PAINT MONO (2810 3885);
FORCEPROP 0 LASTPIN (2800 3925) $PN BW7
J 0
(2810 3935);
DISPLAY 0.680851 (2810 3935);
PAINT MONO (2810 3935);
FORCEPROP 1 LAST CDS_LMAN_SYM_OUTLINE -1050,1350,1050,-1350
J 0
(1600 2725);
DISPLAY 0.468085 (1600 2725);
PAINT GREEN (1600 2725);
DISPLAY INVISIBLE (1600 2725);
FORCEPROP 1 LAST NEEDS_NO_SIZE TRUE
J 0
(1600 2725);
DISPLAY 0.723404 (1600 2725);
PAINT GREEN (1600 2725);
DISPLAY INVISIBLE (1600 2725);
FORCEPROP 2 LAST CDS_LIB pure_quanta
J 0
(1600 2725);
DISPLAY INVISIBLE (1600 2725);
FORCEPROP 2 LAST CDS_LOCATION U1
J 0
(550 4400);
DISPLAY 1.021277 (550 4400);
DISPLAY INVISIBLE (550 4400);
FORCEPROP 0 LAST $SEC 23
J 0
(550 4400);
DISPLAY 0.680851 (550 4400);
PAINT MONO (550 4400);
DISPLAY INVISIBLE (550 4400);
FORCEPROP 2 LAST CDS_SEC 23
J 0
(550 4400);
DISPLAY 1.021277 (550 4400);
DISPLAY INVISIBLE (550 4400);
FORCEPROP 1 LAST PATH I21
J 0
(1600 2725);
DISPLAY 0.723404 (1600 2725);
PAINT GREEN (1600 2725);
DISPLAY INVISIBLE (1600 2725);
FORCEADD TAP..1
R 2
(-100 2525);
FORCEPROP 3 LASTPIN (-50 2525) SIG_NAME UPI_CPU0_CPU1_P0P1_DN<20>
J 0
(-40 2535);
DISPLAY 0.659574 (-40 2535);
PAINT MONO (-40 2535);
DISPLAY INVISIBLE (-40 2535);
FORCEPROP 1 LASTPIN (-50 2525) BN 20
J 2
(-38 2533);
DISPLAY 0.680851 (-38 2533);
PAINT GREEN (-38 2533);
FORCEPROP 2 LAST CDS_LIB standard
J 0
(-100 2525);
PAINT MONO (-100 2525);
DISPLAY INVISIBLE (-100 2525);
FORCEPROP 1 LAST BODY_TYPE PLUMBING
J 2
(-100 2575);
DISPLAY 0.872340 (-100 2575);
PAINT GREEN (-100 2575);
DISPLAY INVISIBLE (-100 2575);
FORCEPROP 1 LAST HDL_TAP TRUE
J 2
(-425 2400);
DISPLAY 0.872340 (-425 2400);
DISPLAY INVISIBLE (-425 2400);
FORCEPROP 1 LAST PATH I23
J 2
(-98 2525);
DISPLAY 0.872340 (-98 2525);
PAINT GREEN (-98 2525);
DISPLAY INVISIBLE (-98 2525);
FORCEADD TAP..1
R 2
(-100 2575);
FORCEPROP 3 LASTPIN (-50 2575) SIG_NAME UPI_CPU0_CPU1_P0P1_DN<21>
J 0
(-40 2585);
DISPLAY 0.659574 (-40 2585);
PAINT MONO (-40 2585);
DISPLAY INVISIBLE (-40 2585);
FORCEPROP 1 LASTPIN (-50 2575) BN 21
J 2
(-38 2583);
DISPLAY 0.680851 (-38 2583);
PAINT GREEN (-38 2583);
FORCEPROP 2 LAST CDS_LIB standard
J 0
(-100 2575);
PAINT MONO (-100 2575);
DISPLAY INVISIBLE (-100 2575);
FORCEPROP 1 LAST BODY_TYPE PLUMBING
J 2
(-100 2625);
DISPLAY 0.872340 (-100 2625);
PAINT GREEN (-100 2625);
DISPLAY INVISIBLE (-100 2625);
FORCEPROP 1 LAST HDL_TAP TRUE
J 2
(-425 2450);
DISPLAY 0.872340 (-425 2450);
DISPLAY INVISIBLE (-425 2450);
FORCEPROP 1 LAST PATH I25
J 2
(-98 2575);
DISPLAY 0.872340 (-98 2575);
PAINT GREEN (-98 2575);
DISPLAY INVISIBLE (-98 2575);
FORCEADD TAP..1
R 2
(-100 2625);
FORCEPROP 3 LASTPIN (-50 2625) SIG_NAME UPI_CPU0_CPU1_P0P1_DN<22>
J 0
(-40 2635);
DISPLAY 0.659574 (-40 2635);
PAINT MONO (-40 2635);
DISPLAY INVISIBLE (-40 2635);
FORCEPROP 1 LASTPIN (-50 2625) BN 22
J 2
(-38 2633);
DISPLAY 0.680851 (-38 2633);
PAINT GREEN (-38 2633);
FORCEPROP 2 LAST CDS_LIB standard
J 0
(-100 2625);
PAINT MONO (-100 2625);
DISPLAY INVISIBLE (-100 2625);
FORCEPROP 1 LAST BODY_TYPE PLUMBING
J 2
(-100 2675);
DISPLAY 0.872340 (-100 2675);
PAINT GREEN (-100 2675);
DISPLAY INVISIBLE (-100 2675);
FORCEPROP 1 LAST HDL_TAP TRUE
J 2
(-425 2500);
DISPLAY 0.872340 (-425 2500);
DISPLAY INVISIBLE (-425 2500);
FORCEPROP 1 LAST PATH I26
J 2
(-98 2625);
DISPLAY 0.872340 (-98 2625);
PAINT GREEN (-98 2625);
DISPLAY INVISIBLE (-98 2625);
FORCEADD TAP..1
R 2
(-100 2775);
FORCEPROP 3 LASTPIN (-50 2775) SIG_NAME UPI_CPU0_CPU1_P0P1_DP<0>
J 0
(-40 2785);
DISPLAY 0.659574 (-40 2785);
PAINT MONO (-40 2785);
DISPLAY INVISIBLE (-40 2785);
FORCEPROP 1 LASTPIN (-50 2775) BN 0
J 2
(-38 2783);
DISPLAY 0.680851 (-38 2783);
PAINT GREEN (-38 2783);
FORCEPROP 2 LAST CDS_LIB standard
J 0
(-100 2775);
DISPLAY INVISIBLE (-100 2775);
FORCEPROP 1 LAST BODY_TYPE PLUMBING
J 2
(-100 2825);
DISPLAY 0.872340 (-100 2825);
PAINT GREEN (-100 2825);
DISPLAY INVISIBLE (-100 2825);
FORCEPROP 1 LAST HDL_TAP TRUE
J 2
(-425 2650);
DISPLAY 0.872340 (-425 2650);
DISPLAY INVISIBLE (-425 2650);
FORCEPROP 1 LAST PATH I28
J 2
(-98 2775);
DISPLAY 0.872340 (-98 2775);
PAINT GREEN (-98 2775);
DISPLAY INVISIBLE (-98 2775);
FORCEADD TAP..1
R 2
(-100 2825);
FORCEPROP 3 LASTPIN (-50 2825) SIG_NAME UPI_CPU0_CPU1_P0P1_DP<1>
J 0
(-40 2835);
DISPLAY 0.659574 (-40 2835);
PAINT MONO (-40 2835);
DISPLAY INVISIBLE (-40 2835);
FORCEPROP 1 LASTPIN (-50 2825) BN 1
J 2
(-38 2833);
DISPLAY 0.680851 (-38 2833);
PAINT GREEN (-38 2833);
FORCEPROP 2 LAST CDS_LIB standard
J 0
(-100 2825);
DISPLAY INVISIBLE (-100 2825);
FORCEPROP 1 LAST BODY_TYPE PLUMBING
J 2
(-100 2875);
DISPLAY 0.872340 (-100 2875);
PAINT GREEN (-100 2875);
DISPLAY INVISIBLE (-100 2875);
FORCEPROP 1 LAST HDL_TAP TRUE
J 2
(-425 2700);
DISPLAY 0.872340 (-425 2700);
DISPLAY INVISIBLE (-425 2700);
FORCEPROP 1 LAST PATH I29
J 2
(-98 2825);
DISPLAY 0.872340 (-98 2825);
PAINT GREEN (-98 2825);
DISPLAY INVISIBLE (-98 2825);
FORCEADD TAP..1
R 2
(-100 2875);
FORCEPROP 3 LASTPIN (-50 2875) SIG_NAME UPI_CPU0_CPU1_P0P1_DP<2>
J 0
(-40 2885);
DISPLAY 0.659574 (-40 2885);
PAINT MONO (-40 2885);
DISPLAY INVISIBLE (-40 2885);
FORCEPROP 1 LASTPIN (-50 2875) BN 2
J 2
(-38 2883);
DISPLAY 0.680851 (-38 2883);
PAINT GREEN (-38 2883);
FORCEPROP 2 LAST CDS_LIB standard
J 0
(-100 2875);
DISPLAY INVISIBLE (-100 2875);
FORCEPROP 1 LAST BODY_TYPE PLUMBING
J 2
(-100 2925);
DISPLAY 0.872340 (-100 2925);
PAINT GREEN (-100 2925);
DISPLAY INVISIBLE (-100 2925);
FORCEPROP 1 LAST HDL_TAP TRUE
J 2
(-425 2750);
DISPLAY 0.872340 (-425 2750);
DISPLAY INVISIBLE (-425 2750);
FORCEPROP 1 LAST PATH I30
J 2
(-98 2875);
DISPLAY 0.872340 (-98 2875);
PAINT GREEN (-98 2875);
DISPLAY INVISIBLE (-98 2875);
FORCEADD TAP..1
R 2
(-100 2925);
FORCEPROP 3 LASTPIN (-50 2925) SIG_NAME UPI_CPU0_CPU1_P0P1_DP<3>
J 0
(-40 2935);
DISPLAY 0.659574 (-40 2935);
PAINT MONO (-40 2935);
DISPLAY INVISIBLE (-40 2935);
FORCEPROP 1 LASTPIN (-50 2925) BN 3
J 2
(-38 2933);
DISPLAY 0.680851 (-38 2933);
PAINT GREEN (-38 2933);
FORCEPROP 2 LAST CDS_LIB standard
J 0
(-100 2925);
DISPLAY INVISIBLE (-100 2925);
FORCEPROP 1 LAST BODY_TYPE PLUMBING
J 2
(-100 2975);
DISPLAY 0.872340 (-100 2975);
PAINT GREEN (-100 2975);
DISPLAY INVISIBLE (-100 2975);
FORCEPROP 1 LAST HDL_TAP TRUE
J 2
(-425 2800);
DISPLAY 0.872340 (-425 2800);
DISPLAY INVISIBLE (-425 2800);
FORCEPROP 1 LAST PATH I31
J 2
(-98 2925);
DISPLAY 0.872340 (-98 2925);
PAINT GREEN (-98 2925);
DISPLAY INVISIBLE (-98 2925);
FORCEADD TAP..1
R 2
(-100 3025);
FORCEPROP 3 LASTPIN (-50 3025) SIG_NAME UPI_CPU0_CPU1_P0P1_DP<5>
J 0
(-40 3035);
DISPLAY 0.659574 (-40 3035);
PAINT MONO (-40 3035);
DISPLAY INVISIBLE (-40 3035);
FORCEPROP 1 LASTPIN (-50 3025) BN 5
J 2
(-38 3033);
DISPLAY 0.680851 (-38 3033);
PAINT GREEN (-38 3033);
FORCEPROP 2 LAST CDS_LIB standard
J 0
(-100 3025);
DISPLAY INVISIBLE (-100 3025);
FORCEPROP 1 LAST BODY_TYPE PLUMBING
J 2
(-100 3075);
DISPLAY 0.872340 (-100 3075);
PAINT GREEN (-100 3075);
DISPLAY INVISIBLE (-100 3075);
FORCEPROP 1 LAST HDL_TAP TRUE
J 2
(-425 2900);
DISPLAY 0.872340 (-425 2900);
DISPLAY INVISIBLE (-425 2900);
FORCEPROP 1 LAST PATH I32
J 2
(-98 3025);
DISPLAY 0.872340 (-98 3025);
PAINT GREEN (-98 3025);
DISPLAY INVISIBLE (-98 3025);
FORCEADD TAP..1
R 2
(-100 2975);
FORCEPROP 3 LASTPIN (-50 2975) SIG_NAME UPI_CPU0_CPU1_P0P1_DP<4>
J 0
(-40 2985);
DISPLAY 0.659574 (-40 2985);
PAINT MONO (-40 2985);
DISPLAY INVISIBLE (-40 2985);
FORCEPROP 1 LASTPIN (-50 2975) BN 4
J 2
(-38 2983);
DISPLAY 0.680851 (-38 2983);
PAINT GREEN (-38 2983);
FORCEPROP 2 LAST CDS_LIB standard
J 0
(-100 2975);
DISPLAY INVISIBLE (-100 2975);
FORCEPROP 1 LAST BODY_TYPE PLUMBING
J 2
(-100 3025);
DISPLAY 0.872340 (-100 3025);
PAINT GREEN (-100 3025);
DISPLAY INVISIBLE (-100 3025);
FORCEPROP 1 LAST HDL_TAP TRUE
J 2
(-425 2850);
DISPLAY 0.872340 (-425 2850);
DISPLAY INVISIBLE (-425 2850);
FORCEPROP 1 LAST PATH I33
J 2
(-98 2975);
DISPLAY 0.872340 (-98 2975);
PAINT GREEN (-98 2975);
DISPLAY INVISIBLE (-98 2975);
FORCEADD TAP..1
R 2
(-100 3075);
FORCEPROP 3 LASTPIN (-50 3075) SIG_NAME UPI_CPU0_CPU1_P0P1_DP<6>
J 0
(-40 3085);
DISPLAY 0.659574 (-40 3085);
PAINT MONO (-40 3085);
DISPLAY INVISIBLE (-40 3085);
FORCEPROP 1 LASTPIN (-50 3075) BN 6
J 2
(-38 3083);
DISPLAY 0.680851 (-38 3083);
PAINT GREEN (-38 3083);
FORCEPROP 2 LAST CDS_LIB standard
J 0
(-100 3075);
DISPLAY INVISIBLE (-100 3075);
FORCEPROP 1 LAST BODY_TYPE PLUMBING
J 2
(-100 3125);
DISPLAY 0.872340 (-100 3125);
PAINT GREEN (-100 3125);
DISPLAY INVISIBLE (-100 3125);
FORCEPROP 1 LAST HDL_TAP TRUE
J 2
(-425 2950);
DISPLAY 0.872340 (-425 2950);
DISPLAY INVISIBLE (-425 2950);
FORCEPROP 1 LAST PATH I34
J 2
(-98 3075);
DISPLAY 0.872340 (-98 3075);
PAINT GREEN (-98 3075);
DISPLAY INVISIBLE (-98 3075);
FORCEADD TAP..1
R 2
(-100 3125);
FORCEPROP 3 LASTPIN (-50 3125) SIG_NAME UPI_CPU0_CPU1_P0P1_DP<7>
J 0
(-40 3135);
DISPLAY 0.659574 (-40 3135);
PAINT MONO (-40 3135);
DISPLAY INVISIBLE (-40 3135);
FORCEPROP 1 LASTPIN (-50 3125) BN 7
J 2
(-38 3133);
DISPLAY 0.680851 (-38 3133);
PAINT GREEN (-38 3133);
FORCEPROP 2 LAST CDS_LIB standard
J 0
(-100 3125);
DISPLAY INVISIBLE (-100 3125);
FORCEPROP 1 LAST BODY_TYPE PLUMBING
J 2
(-100 3175);
DISPLAY 0.872340 (-100 3175);
PAINT GREEN (-100 3175);
DISPLAY INVISIBLE (-100 3175);
FORCEPROP 1 LAST HDL_TAP TRUE
J 2
(-425 3000);
DISPLAY 0.872340 (-425 3000);
DISPLAY INVISIBLE (-425 3000);
FORCEPROP 1 LAST PATH I35
J 2
(-98 3125);
DISPLAY 0.872340 (-98 3125);
PAINT GREEN (-98 3125);
DISPLAY INVISIBLE (-98 3125);
FORCEADD TAP..1
R 2
(-100 3175);
FORCEPROP 3 LASTPIN (-50 3175) SIG_NAME UPI_CPU0_CPU1_P0P1_DP<8>
J 0
(-40 3185);
DISPLAY 0.659574 (-40 3185);
PAINT MONO (-40 3185);
DISPLAY INVISIBLE (-40 3185);
FORCEPROP 1 LASTPIN (-50 3175) BN 8
J 2
(-38 3183);
DISPLAY 0.680851 (-38 3183);
PAINT GREEN (-38 3183);
FORCEPROP 2 LAST CDS_LIB standard
J 0
(-100 3175);
DISPLAY INVISIBLE (-100 3175);
FORCEPROP 1 LAST BODY_TYPE PLUMBING
J 2
(-100 3225);
DISPLAY 0.872340 (-100 3225);
PAINT GREEN (-100 3225);
DISPLAY INVISIBLE (-100 3225);
FORCEPROP 1 LAST HDL_TAP TRUE
J 2
(-425 3050);
DISPLAY 0.872340 (-425 3050);
DISPLAY INVISIBLE (-425 3050);
FORCEPROP 1 LAST PATH I36
J 2
(-98 3175);
DISPLAY 0.872340 (-98 3175);
PAINT GREEN (-98 3175);
DISPLAY INVISIBLE (-98 3175);
FORCEADD TAP..1
R 2
(-100 3225);
FORCEPROP 3 LASTPIN (-50 3225) SIG_NAME UPI_CPU0_CPU1_P0P1_DP<9>
J 0
(-40 3235);
DISPLAY 0.659574 (-40 3235);
PAINT MONO (-40 3235);
DISPLAY INVISIBLE (-40 3235);
FORCEPROP 1 LASTPIN (-50 3225) BN 9
J 2
(-38 3233);
DISPLAY 0.680851 (-38 3233);
PAINT GREEN (-38 3233);
FORCEPROP 2 LAST CDS_LIB standard
J 0
(-100 3225);
DISPLAY INVISIBLE (-100 3225);
FORCEPROP 1 LAST BODY_TYPE PLUMBING
J 2
(-100 3275);
DISPLAY 0.872340 (-100 3275);
PAINT GREEN (-100 3275);
DISPLAY INVISIBLE (-100 3275);
FORCEPROP 1 LAST HDL_TAP TRUE
J 2
(-425 3100);
DISPLAY 0.872340 (-425 3100);
DISPLAY INVISIBLE (-425 3100);
FORCEPROP 1 LAST PATH I37
J 2
(-98 3225);
DISPLAY 0.872340 (-98 3225);
PAINT GREEN (-98 3225);
DISPLAY INVISIBLE (-98 3225);
FORCEADD TAP..1
R 2
(-100 3275);
FORCEPROP 3 LASTPIN (-50 3275) SIG_NAME UPI_CPU0_CPU1_P0P1_DP<10>
J 0
(-40 3285);
DISPLAY 0.659574 (-40 3285);
PAINT MONO (-40 3285);
DISPLAY INVISIBLE (-40 3285);
FORCEPROP 1 LASTPIN (-50 3275) BN 10
J 2
(-38 3283);
DISPLAY 0.680851 (-38 3283);
PAINT GREEN (-38 3283);
FORCEPROP 2 LAST CDS_LIB standard
J 0
(-100 3275);
DISPLAY INVISIBLE (-100 3275);
FORCEPROP 1 LAST BODY_TYPE PLUMBING
J 2
(-100 3325);
DISPLAY 0.872340 (-100 3325);
PAINT GREEN (-100 3325);
DISPLAY INVISIBLE (-100 3325);
FORCEPROP 1 LAST HDL_TAP TRUE
J 2
(-425 3150);
DISPLAY 0.872340 (-425 3150);
DISPLAY INVISIBLE (-425 3150);
FORCEPROP 1 LAST PATH I38
J 2
(-98 3275);
DISPLAY 0.872340 (-98 3275);
PAINT GREEN (-98 3275);
DISPLAY INVISIBLE (-98 3275);
FORCEADD TAP..1
R 2
(-100 3325);
FORCEPROP 3 LASTPIN (-50 3325) SIG_NAME UPI_CPU0_CPU1_P0P1_DP<11>
J 0
(-40 3335);
DISPLAY 0.659574 (-40 3335);
PAINT MONO (-40 3335);
DISPLAY INVISIBLE (-40 3335);
FORCEPROP 1 LASTPIN (-50 3325) BN 11
J 2
(-38 3333);
DISPLAY 0.680851 (-38 3333);
PAINT GREEN (-38 3333);
FORCEPROP 2 LAST CDS_LIB standard
J 0
(-100 3325);
DISPLAY INVISIBLE (-100 3325);
FORCEPROP 1 LAST BODY_TYPE PLUMBING
J 2
(-100 3375);
DISPLAY 0.872340 (-100 3375);
PAINT GREEN (-100 3375);
DISPLAY INVISIBLE (-100 3375);
FORCEPROP 1 LAST HDL_TAP TRUE
J 2
(-425 3200);
DISPLAY 0.872340 (-425 3200);
DISPLAY INVISIBLE (-425 3200);
FORCEPROP 1 LAST PATH I39
J 2
(-98 3325);
DISPLAY 0.872340 (-98 3325);
PAINT GREEN (-98 3325);
DISPLAY INVISIBLE (-98 3325);
FORCEADD TAP..1
R 2
(-100 3475);
FORCEPROP 3 LASTPIN (-50 3475) SIG_NAME UPI_CPU0_CPU1_P0P1_DP<14>
J 0
(-40 3485);
DISPLAY 0.659574 (-40 3485);
PAINT MONO (-40 3485);
DISPLAY INVISIBLE (-40 3485);
FORCEPROP 1 LASTPIN (-50 3475) BN 14
J 2
(-38 3483);
DISPLAY 0.680851 (-38 3483);
PAINT GREEN (-38 3483);
FORCEPROP 2 LAST CDS_LIB standard
J 0
(-100 3475);
DISPLAY INVISIBLE (-100 3475);
FORCEPROP 1 LAST BODY_TYPE PLUMBING
J 2
(-100 3525);
DISPLAY 0.872340 (-100 3525);
PAINT GREEN (-100 3525);
DISPLAY INVISIBLE (-100 3525);
FORCEPROP 1 LAST HDL_TAP TRUE
J 2
(-425 3350);
DISPLAY 0.872340 (-425 3350);
DISPLAY INVISIBLE (-425 3350);
FORCEPROP 1 LAST PATH I41
J 2
(-98 3475);
DISPLAY 0.872340 (-98 3475);
PAINT GREEN (-98 3475);
DISPLAY INVISIBLE (-98 3475);
FORCEADD TAP..1
R 2
(-100 3575);
FORCEPROP 3 LASTPIN (-50 3575) SIG_NAME UPI_CPU0_CPU1_P0P1_DP<16>
J 0
(-40 3585);
DISPLAY 0.659574 (-40 3585);
PAINT MONO (-40 3585);
DISPLAY INVISIBLE (-40 3585);
FORCEPROP 1 LASTPIN (-50 3575) BN 16
J 2
(-38 3583);
DISPLAY 0.680851 (-38 3583);
PAINT GREEN (-38 3583);
FORCEPROP 2 LAST CDS_LIB standard
J 0
(-100 3575);
DISPLAY INVISIBLE (-100 3575);
FORCEPROP 1 LAST BODY_TYPE PLUMBING
J 2
(-100 3625);
DISPLAY 0.872340 (-100 3625);
PAINT GREEN (-100 3625);
DISPLAY INVISIBLE (-100 3625);
FORCEPROP 1 LAST HDL_TAP TRUE
J 2
(-425 3450);
DISPLAY 0.872340 (-425 3450);
DISPLAY INVISIBLE (-425 3450);
FORCEPROP 1 LAST PATH I44
J 2
(-98 3575);
DISPLAY 0.872340 (-98 3575);
PAINT GREEN (-98 3575);
DISPLAY INVISIBLE (-98 3575);
FORCEADD TAP..1
R 2
(-100 3625);
FORCEPROP 3 LASTPIN (-50 3625) SIG_NAME UPI_CPU0_CPU1_P0P1_DP<17>
J 0
(-40 3635);
DISPLAY 0.659574 (-40 3635);
PAINT MONO (-40 3635);
DISPLAY INVISIBLE (-40 3635);
FORCEPROP 1 LASTPIN (-50 3625) BN 17
J 2
(-38 3633);
DISPLAY 0.680851 (-38 3633);
PAINT GREEN (-38 3633);
FORCEPROP 2 LAST CDS_LIB standard
J 0
(-100 3625);
DISPLAY INVISIBLE (-100 3625);
FORCEPROP 1 LAST BODY_TYPE PLUMBING
J 2
(-100 3675);
DISPLAY 0.872340 (-100 3675);
PAINT GREEN (-100 3675);
DISPLAY INVISIBLE (-100 3675);
FORCEPROP 1 LAST HDL_TAP TRUE
J 2
(-425 3500);
DISPLAY 0.872340 (-425 3500);
DISPLAY INVISIBLE (-425 3500);
FORCEPROP 1 LAST PATH I45
J 2
(-98 3625);
DISPLAY 0.872340 (-98 3625);
PAINT GREEN (-98 3625);
DISPLAY INVISIBLE (-98 3625);
FORCEADD TAP..1
R 2
(-100 3675);
FORCEPROP 3 LASTPIN (-50 3675) SIG_NAME UPI_CPU0_CPU1_P0P1_DP<18>
J 0
(-40 3685);
DISPLAY 0.659574 (-40 3685);
PAINT MONO (-40 3685);
DISPLAY INVISIBLE (-40 3685);
FORCEPROP 1 LASTPIN (-50 3675) BN 18
J 2
(-38 3683);
DISPLAY 0.680851 (-38 3683);
PAINT GREEN (-38 3683);
FORCEPROP 2 LAST CDS_LIB standard
J 0
(-100 3675);
DISPLAY INVISIBLE (-100 3675);
FORCEPROP 1 LAST BODY_TYPE PLUMBING
J 2
(-100 3725);
DISPLAY 0.872340 (-100 3725);
PAINT GREEN (-100 3725);
DISPLAY INVISIBLE (-100 3725);
FORCEPROP 1 LAST HDL_TAP TRUE
J 2
(-425 3550);
DISPLAY 0.872340 (-425 3550);
DISPLAY INVISIBLE (-425 3550);
FORCEPROP 1 LAST PATH I46
J 2
(-98 3675);
DISPLAY 0.872340 (-98 3675);
PAINT GREEN (-98 3675);
DISPLAY INVISIBLE (-98 3675);
FORCEADD TAP..1
R 2
(-100 3725);
FORCEPROP 3 LASTPIN (-50 3725) SIG_NAME UPI_CPU0_CPU1_P0P1_DP<19>
J 0
(-40 3735);
DISPLAY 0.659574 (-40 3735);
PAINT MONO (-40 3735);
DISPLAY INVISIBLE (-40 3735);
FORCEPROP 1 LASTPIN (-50 3725) BN 19
J 2
(-38 3733);
DISPLAY 0.680851 (-38 3733);
PAINT GREEN (-38 3733);
FORCEPROP 2 LAST CDS_LIB standard
J 0
(-100 3725);
DISPLAY INVISIBLE (-100 3725);
FORCEPROP 1 LAST BODY_TYPE PLUMBING
J 2
(-100 3775);
DISPLAY 0.872340 (-100 3775);
PAINT GREEN (-100 3775);
DISPLAY INVISIBLE (-100 3775);
FORCEPROP 1 LAST HDL_TAP TRUE
J 2
(-425 3600);
DISPLAY 0.872340 (-425 3600);
DISPLAY INVISIBLE (-425 3600);
FORCEPROP 1 LAST PATH I47
J 2
(-98 3725);
DISPLAY 0.872340 (-98 3725);
PAINT GREEN (-98 3725);
DISPLAY INVISIBLE (-98 3725);
FORCEADD TAP..1
R 2
(-100 3925);
FORCEPROP 3 LASTPIN (-50 3925) SIG_NAME UPI_CPU0_CPU1_P0P1_DP<23>
J 0
(-40 3935);
DISPLAY 0.659574 (-40 3935);
PAINT MONO (-40 3935);
DISPLAY INVISIBLE (-40 3935);
FORCEPROP 1 LASTPIN (-50 3925) BN 23
J 2
(-38 3933);
DISPLAY 0.680851 (-38 3933);
PAINT GREEN (-38 3933);
FORCEPROP 2 LAST CDS_LIB standard
J 0
(-100 3925);
DISPLAY INVISIBLE (-100 3925);
FORCEPROP 1 LAST BODY_TYPE PLUMBING
J 2
(-100 3975);
DISPLAY 0.872340 (-100 3975);
PAINT GREEN (-100 3975);
DISPLAY INVISIBLE (-100 3975);
FORCEPROP 1 LAST HDL_TAP TRUE
J 2
(-425 3800);
DISPLAY 0.872340 (-425 3800);
DISPLAY INVISIBLE (-425 3800);
FORCEPROP 1 LAST PATH I51
J 2
(-98 3925);
DISPLAY 0.872340 (-98 3925);
PAINT GREEN (-98 3925);
DISPLAY INVISIBLE (-98 3925);
FORCEADD TAP..1
(3275 1525);
FORCEPROP 3 LASTPIN (3225 1525) SIG_NAME UPI_CPU1_CPU0_P1P0_DN<0>
J 0
(3235 1535);
DISPLAY 0.659574 (3235 1535);
PAINT MONO (3235 1535);
DISPLAY INVISIBLE (3235 1535);
FORCEPROP 1 LASTPIN (3225 1525) BN 0
J 0
(3213 1533);
DISPLAY 0.680851 (3213 1533);
PAINT GREEN (3213 1533);
FORCEPROP 2 LAST CDS_LIB standard
J 0
(3275 1525);
PAINT MONO (3275 1525);
DISPLAY INVISIBLE (3275 1525);
FORCEPROP 1 LAST BODY_TYPE PLUMBING
J 0
(3275 1575);
DISPLAY 0.872340 (3275 1575);
PAINT GREEN (3275 1575);
DISPLAY INVISIBLE (3275 1575);
FORCEPROP 1 LAST HDL_TAP TRUE
J 0
(3600 1400);
DISPLAY 0.872340 (3600 1400);
DISPLAY INVISIBLE (3600 1400);
FORCEPROP 1 LAST PATH I52
J 0
(3273 1525);
DISPLAY 0.872340 (3273 1525);
PAINT GREEN (3273 1525);
DISPLAY INVISIBLE (3273 1525);
FORCEADD TAP..1
(3275 1575);
FORCEPROP 3 LASTPIN (3225 1575) SIG_NAME UPI_CPU1_CPU0_P1P0_DN<1>
J 0
(3235 1585);
DISPLAY 0.659574 (3235 1585);
PAINT MONO (3235 1585);
DISPLAY INVISIBLE (3235 1585);
FORCEPROP 1 LASTPIN (3225 1575) BN 1
J 0
(3213 1583);
DISPLAY 0.680851 (3213 1583);
PAINT GREEN (3213 1583);
FORCEPROP 2 LAST CDS_LIB standard
J 0
(3275 1575);
PAINT MONO (3275 1575);
DISPLAY INVISIBLE (3275 1575);
FORCEPROP 1 LAST BODY_TYPE PLUMBING
J 0
(3275 1625);
DISPLAY 0.872340 (3275 1625);
PAINT GREEN (3275 1625);
DISPLAY INVISIBLE (3275 1625);
FORCEPROP 1 LAST HDL_TAP TRUE
J 0
(3600 1450);
DISPLAY 0.872340 (3600 1450);
DISPLAY INVISIBLE (3600 1450);
FORCEPROP 1 LAST PATH I53
J 0
(3273 1575);
DISPLAY 0.872340 (3273 1575);
PAINT GREEN (3273 1575);
DISPLAY INVISIBLE (3273 1575);
FORCEADD TAP..1
(3275 1625);
FORCEPROP 3 LASTPIN (3225 1625) SIG_NAME UPI_CPU1_CPU0_P1P0_DN<2>
J 0
(3235 1635);
DISPLAY 0.659574 (3235 1635);
PAINT MONO (3235 1635);
DISPLAY INVISIBLE (3235 1635);
FORCEPROP 1 LASTPIN (3225 1625) BN 2
J 0
(3213 1633);
DISPLAY 0.680851 (3213 1633);
PAINT GREEN (3213 1633);
FORCEPROP 2 LAST CDS_LIB standard
J 0
(3275 1625);
PAINT MONO (3275 1625);
DISPLAY INVISIBLE (3275 1625);
FORCEPROP 1 LAST BODY_TYPE PLUMBING
J 0
(3275 1675);
DISPLAY 0.872340 (3275 1675);
PAINT GREEN (3275 1675);
DISPLAY INVISIBLE (3275 1675);
FORCEPROP 1 LAST HDL_TAP TRUE
J 0
(3600 1500);
DISPLAY 0.872340 (3600 1500);
DISPLAY INVISIBLE (3600 1500);
FORCEPROP 1 LAST PATH I54
J 0
(3273 1625);
DISPLAY 0.872340 (3273 1625);
PAINT GREEN (3273 1625);
DISPLAY INVISIBLE (3273 1625);
FORCEADD TAP..1
(3275 1675);
FORCEPROP 3 LASTPIN (3225 1675) SIG_NAME UPI_CPU1_CPU0_P1P0_DN<3>
J 0
(3235 1685);
DISPLAY 0.659574 (3235 1685);
PAINT MONO (3235 1685);
DISPLAY INVISIBLE (3235 1685);
FORCEPROP 1 LASTPIN (3225 1675) BN 3
J 0
(3213 1683);
DISPLAY 0.680851 (3213 1683);
PAINT GREEN (3213 1683);
FORCEPROP 2 LAST CDS_LIB standard
J 0
(3275 1675);
PAINT MONO (3275 1675);
DISPLAY INVISIBLE (3275 1675);
FORCEPROP 1 LAST BODY_TYPE PLUMBING
J 0
(3275 1725);
DISPLAY 0.872340 (3275 1725);
PAINT GREEN (3275 1725);
DISPLAY INVISIBLE (3275 1725);
FORCEPROP 1 LAST HDL_TAP TRUE
J 0
(3600 1550);
DISPLAY 0.872340 (3600 1550);
DISPLAY INVISIBLE (3600 1550);
FORCEPROP 1 LAST PATH I55
J 0
(3273 1675);
DISPLAY 0.872340 (3273 1675);
PAINT GREEN (3273 1675);
DISPLAY INVISIBLE (3273 1675);
FORCEADD TAP..1
(3275 1825);
FORCEPROP 3 LASTPIN (3225 1825) SIG_NAME UPI_CPU1_CPU0_P1P0_DN<6>
J 0
(3235 1835);
DISPLAY 0.659574 (3235 1835);
PAINT MONO (3235 1835);
DISPLAY INVISIBLE (3235 1835);
FORCEPROP 1 LASTPIN (3225 1825) BN 6
J 0
(3213 1833);
DISPLAY 0.680851 (3213 1833);
PAINT GREEN (3213 1833);
FORCEPROP 2 LAST CDS_LIB standard
J 0
(3275 1825);
PAINT MONO (3275 1825);
DISPLAY INVISIBLE (3275 1825);
FORCEPROP 1 LAST BODY_TYPE PLUMBING
J 0
(3275 1875);
DISPLAY 0.872340 (3275 1875);
PAINT GREEN (3275 1875);
DISPLAY INVISIBLE (3275 1875);
FORCEPROP 1 LAST HDL_TAP TRUE
J 0
(3600 1700);
DISPLAY 0.872340 (3600 1700);
DISPLAY INVISIBLE (3600 1700);
FORCEPROP 1 LAST PATH I56
J 0
(3273 1825);
DISPLAY 0.872340 (3273 1825);
PAINT GREEN (3273 1825);
DISPLAY INVISIBLE (3273 1825);
FORCEADD TAP..1
(3275 1875);
FORCEPROP 3 LASTPIN (3225 1875) SIG_NAME UPI_CPU1_CPU0_P1P0_DN<7>
J 0
(3235 1885);
DISPLAY 0.659574 (3235 1885);
PAINT MONO (3235 1885);
DISPLAY INVISIBLE (3235 1885);
FORCEPROP 1 LASTPIN (3225 1875) BN 7
J 0
(3213 1883);
DISPLAY 0.680851 (3213 1883);
PAINT GREEN (3213 1883);
FORCEPROP 2 LAST CDS_LIB standard
J 0
(3275 1875);
PAINT MONO (3275 1875);
DISPLAY INVISIBLE (3275 1875);
FORCEPROP 1 LAST BODY_TYPE PLUMBING
J 0
(3275 1925);
DISPLAY 0.872340 (3275 1925);
PAINT GREEN (3275 1925);
DISPLAY INVISIBLE (3275 1925);
FORCEPROP 1 LAST HDL_TAP TRUE
J 0
(3600 1750);
DISPLAY 0.872340 (3600 1750);
DISPLAY INVISIBLE (3600 1750);
FORCEPROP 1 LAST PATH I57
J 0
(3273 1875);
DISPLAY 0.872340 (3273 1875);
PAINT GREEN (3273 1875);
DISPLAY INVISIBLE (3273 1875);
FORCEADD TAP..1
(3275 1725);
FORCEPROP 3 LASTPIN (3225 1725) SIG_NAME UPI_CPU1_CPU0_P1P0_DN<4>
J 0
(3235 1735);
DISPLAY 0.659574 (3235 1735);
PAINT MONO (3235 1735);
DISPLAY INVISIBLE (3235 1735);
FORCEPROP 1 LASTPIN (3225 1725) BN 4
J 0
(3213 1733);
DISPLAY 0.680851 (3213 1733);
PAINT GREEN (3213 1733);
FORCEPROP 2 LAST CDS_LIB standard
J 0
(3275 1725);
PAINT MONO (3275 1725);
DISPLAY INVISIBLE (3275 1725);
FORCEPROP 1 LAST BODY_TYPE PLUMBING
J 0
(3275 1775);
DISPLAY 0.872340 (3275 1775);
PAINT GREEN (3275 1775);
DISPLAY INVISIBLE (3275 1775);
FORCEPROP 1 LAST HDL_TAP TRUE
J 0
(3600 1600);
DISPLAY 0.872340 (3600 1600);
DISPLAY INVISIBLE (3600 1600);
FORCEPROP 1 LAST PATH I58
J 0
(3273 1725);
DISPLAY 0.872340 (3273 1725);
PAINT GREEN (3273 1725);
DISPLAY INVISIBLE (3273 1725);
FORCEADD TAP..1
(3275 1775);
FORCEPROP 3 LASTPIN (3225 1775) SIG_NAME UPI_CPU1_CPU0_P1P0_DN<5>
J 0
(3235 1785);
DISPLAY 0.659574 (3235 1785);
PAINT MONO (3235 1785);
DISPLAY INVISIBLE (3235 1785);
FORCEPROP 1 LASTPIN (3225 1775) BN 5
J 0
(3213 1783);
DISPLAY 0.680851 (3213 1783);
PAINT GREEN (3213 1783);
FORCEPROP 2 LAST CDS_LIB standard
J 0
(3275 1775);
PAINT MONO (3275 1775);
DISPLAY INVISIBLE (3275 1775);
FORCEPROP 1 LAST BODY_TYPE PLUMBING
J 0
(3275 1825);
DISPLAY 0.872340 (3275 1825);
PAINT GREEN (3275 1825);
DISPLAY INVISIBLE (3275 1825);
FORCEPROP 1 LAST HDL_TAP TRUE
J 0
(3600 1650);
DISPLAY 0.872340 (3600 1650);
DISPLAY INVISIBLE (3600 1650);
FORCEPROP 1 LAST PATH I59
J 0
(3273 1775);
DISPLAY 0.872340 (3273 1775);
PAINT GREEN (3273 1775);
DISPLAY INVISIBLE (3273 1775);
FORCEADD TAP..1
(3275 1975);
FORCEPROP 3 LASTPIN (3225 1975) SIG_NAME UPI_CPU1_CPU0_P1P0_DN<9>
J 0
(3235 1985);
DISPLAY 0.659574 (3235 1985);
PAINT MONO (3235 1985);
DISPLAY INVISIBLE (3235 1985);
FORCEPROP 1 LASTPIN (3225 1975) BN 9
J 0
(3213 1983);
DISPLAY 0.680851 (3213 1983);
PAINT GREEN (3213 1983);
FORCEPROP 2 LAST CDS_LIB standard
J 0
(3275 1975);
PAINT MONO (3275 1975);
DISPLAY INVISIBLE (3275 1975);
FORCEPROP 1 LAST BODY_TYPE PLUMBING
J 0
(3275 2025);
DISPLAY 0.872340 (3275 2025);
PAINT GREEN (3275 2025);
DISPLAY INVISIBLE (3275 2025);
FORCEPROP 1 LAST HDL_TAP TRUE
J 0
(3600 1850);
DISPLAY 0.872340 (3600 1850);
DISPLAY INVISIBLE (3600 1850);
FORCEPROP 1 LAST PATH I60
J 0
(3273 1975);
DISPLAY 0.872340 (3273 1975);
PAINT GREEN (3273 1975);
DISPLAY INVISIBLE (3273 1975);
FORCEADD TAP..1
(3275 2125);
FORCEPROP 3 LASTPIN (3225 2125) SIG_NAME UPI_CPU1_CPU0_P1P0_DN<12>
J 0
(3235 2135);
DISPLAY 0.659574 (3235 2135);
PAINT MONO (3235 2135);
DISPLAY INVISIBLE (3235 2135);
FORCEPROP 1 LASTPIN (3225 2125) BN 12
J 0
(3213 2133);
DISPLAY 0.680851 (3213 2133);
PAINT GREEN (3213 2133);
FORCEPROP 2 LAST CDS_LIB standard
J 0
(3275 2125);
PAINT MONO (3275 2125);
DISPLAY INVISIBLE (3275 2125);
FORCEPROP 1 LAST BODY_TYPE PLUMBING
J 0
(3275 2175);
DISPLAY 0.872340 (3275 2175);
PAINT GREEN (3275 2175);
DISPLAY INVISIBLE (3275 2175);
FORCEPROP 1 LAST HDL_TAP TRUE
J 0
(3600 2000);
DISPLAY 0.872340 (3600 2000);
DISPLAY INVISIBLE (3600 2000);
FORCEPROP 1 LAST PATH I61
J 0
(3273 2125);
DISPLAY 0.872340 (3273 2125);
PAINT GREEN (3273 2125);
DISPLAY INVISIBLE (3273 2125);
FORCEADD TAP..1
(3275 2075);
FORCEPROP 3 LASTPIN (3225 2075) SIG_NAME UPI_CPU1_CPU0_P1P0_DN<11>
J 0
(3235 2085);
DISPLAY 0.659574 (3235 2085);
PAINT MONO (3235 2085);
DISPLAY INVISIBLE (3235 2085);
FORCEPROP 1 LASTPIN (3225 2075) BN 11
J 0
(3213 2083);
DISPLAY 0.680851 (3213 2083);
PAINT GREEN (3213 2083);
FORCEPROP 2 LAST CDS_LIB standard
J 0
(3275 2075);
PAINT MONO (3275 2075);
DISPLAY INVISIBLE (3275 2075);
FORCEPROP 1 LAST BODY_TYPE PLUMBING
J 0
(3275 2125);
DISPLAY 0.872340 (3275 2125);
PAINT GREEN (3275 2125);
DISPLAY INVISIBLE (3275 2125);
FORCEPROP 1 LAST HDL_TAP TRUE
J 0
(3600 1950);
DISPLAY 0.872340 (3600 1950);
DISPLAY INVISIBLE (3600 1950);
FORCEPROP 1 LAST PATH I62
J 0
(3273 2075);
DISPLAY 0.872340 (3273 2075);
PAINT GREEN (3273 2075);
DISPLAY INVISIBLE (3273 2075);
FORCEADD TAP..1
(3275 1925);
FORCEPROP 3 LASTPIN (3225 1925) SIG_NAME UPI_CPU1_CPU0_P1P0_DN<8>
J 0
(3235 1935);
DISPLAY 0.659574 (3235 1935);
PAINT MONO (3235 1935);
DISPLAY INVISIBLE (3235 1935);
FORCEPROP 1 LASTPIN (3225 1925) BN 8
J 0
(3213 1933);
DISPLAY 0.680851 (3213 1933);
PAINT GREEN (3213 1933);
FORCEPROP 2 LAST CDS_LIB standard
J 0
(3275 1925);
PAINT MONO (3275 1925);
DISPLAY INVISIBLE (3275 1925);
FORCEPROP 1 LAST BODY_TYPE PLUMBING
J 0
(3275 1975);
DISPLAY 0.872340 (3275 1975);
PAINT GREEN (3275 1975);
DISPLAY INVISIBLE (3275 1975);
FORCEPROP 1 LAST HDL_TAP TRUE
J 0
(3600 1800);
DISPLAY 0.872340 (3600 1800);
DISPLAY INVISIBLE (3600 1800);
FORCEPROP 1 LAST PATH I63
J 0
(3273 1925);
DISPLAY 0.872340 (3273 1925);
PAINT GREEN (3273 1925);
DISPLAY INVISIBLE (3273 1925);
FORCEADD TAP..1
(3275 2025);
FORCEPROP 3 LASTPIN (3225 2025) SIG_NAME UPI_CPU1_CPU0_P1P0_DN<10>
J 0
(3235 2035);
DISPLAY 0.659574 (3235 2035);
PAINT MONO (3235 2035);
DISPLAY INVISIBLE (3235 2035);
FORCEPROP 1 LASTPIN (3225 2025) BN 10
J 0
(3213 2033);
DISPLAY 0.680851 (3213 2033);
PAINT GREEN (3213 2033);
FORCEPROP 2 LAST CDS_LIB standard
J 0
(3275 2025);
PAINT MONO (3275 2025);
DISPLAY INVISIBLE (3275 2025);
FORCEPROP 1 LAST BODY_TYPE PLUMBING
J 0
(3275 2075);
DISPLAY 0.872340 (3275 2075);
PAINT GREEN (3275 2075);
DISPLAY INVISIBLE (3275 2075);
FORCEPROP 1 LAST HDL_TAP TRUE
J 0
(3600 1900);
DISPLAY 0.872340 (3600 1900);
DISPLAY INVISIBLE (3600 1900);
FORCEPROP 1 LAST PATH I64
J 0
(3273 2025);
DISPLAY 0.872340 (3273 2025);
PAINT GREEN (3273 2025);
DISPLAY INVISIBLE (3273 2025);
FORCEADD TAP..1
(3275 2225);
FORCEPROP 3 LASTPIN (3225 2225) SIG_NAME UPI_CPU1_CPU0_P1P0_DN<14>
J 0
(3235 2235);
DISPLAY 0.659574 (3235 2235);
PAINT MONO (3235 2235);
DISPLAY INVISIBLE (3235 2235);
FORCEPROP 1 LASTPIN (3225 2225) BN 14
J 0
(3213 2233);
DISPLAY 0.680851 (3213 2233);
PAINT GREEN (3213 2233);
FORCEPROP 2 LAST CDS_LIB standard
J 0
(3275 2225);
PAINT MONO (3275 2225);
DISPLAY INVISIBLE (3275 2225);
FORCEPROP 1 LAST BODY_TYPE PLUMBING
J 0
(3275 2275);
DISPLAY 0.872340 (3275 2275);
PAINT GREEN (3275 2275);
DISPLAY INVISIBLE (3275 2275);
FORCEPROP 1 LAST HDL_TAP TRUE
J 0
(3600 2100);
DISPLAY 0.872340 (3600 2100);
DISPLAY INVISIBLE (3600 2100);
FORCEPROP 1 LAST PATH I65
J 0
(3273 2225);
DISPLAY 0.872340 (3273 2225);
PAINT GREEN (3273 2225);
DISPLAY INVISIBLE (3273 2225);
FORCEADD TAP..1
(3275 2375);
FORCEPROP 3 LASTPIN (3225 2375) SIG_NAME UPI_CPU1_CPU0_P1P0_DN<17>
J 0
(3235 2385);
DISPLAY 0.659574 (3235 2385);
PAINT MONO (3235 2385);
DISPLAY INVISIBLE (3235 2385);
FORCEPROP 1 LASTPIN (3225 2375) BN 17
J 0
(3213 2383);
DISPLAY 0.680851 (3213 2383);
PAINT GREEN (3213 2383);
FORCEPROP 2 LAST CDS_LIB standard
J 0
(3275 2375);
DISPLAY INVISIBLE (3275 2375);
FORCEPROP 1 LAST BODY_TYPE PLUMBING
J 0
(3275 2425);
DISPLAY 0.872340 (3275 2425);
PAINT GREEN (3275 2425);
DISPLAY INVISIBLE (3275 2425);
FORCEPROP 1 LAST HDL_TAP TRUE
J 0
(3600 2250);
DISPLAY 0.872340 (3600 2250);
DISPLAY INVISIBLE (3600 2250);
FORCEPROP 1 LAST PATH I66
J 0
(3273 2375);
DISPLAY 0.872340 (3273 2375);
PAINT GREEN (3273 2375);
DISPLAY INVISIBLE (3273 2375);
FORCEADD TAP..1
(3275 2325);
FORCEPROP 3 LASTPIN (3225 2325) SIG_NAME UPI_CPU1_CPU0_P1P0_DN<16>
J 0
(3235 2335);
DISPLAY 0.659574 (3235 2335);
PAINT MONO (3235 2335);
DISPLAY INVISIBLE (3235 2335);
FORCEPROP 1 LASTPIN (3225 2325) BN 16
J 0
(3213 2333);
DISPLAY 0.680851 (3213 2333);
PAINT GREEN (3213 2333);
FORCEPROP 2 LAST CDS_LIB standard
J 0
(3275 2325);
PAINT MONO (3275 2325);
DISPLAY INVISIBLE (3275 2325);
FORCEPROP 1 LAST BODY_TYPE PLUMBING
J 0
(3275 2375);
DISPLAY 0.872340 (3275 2375);
PAINT GREEN (3275 2375);
DISPLAY INVISIBLE (3275 2375);
FORCEPROP 1 LAST HDL_TAP TRUE
J 0
(3600 2200);
DISPLAY 0.872340 (3600 2200);
DISPLAY INVISIBLE (3600 2200);
FORCEPROP 1 LAST PATH I67
J 0
(3273 2325);
DISPLAY 0.872340 (3273 2325);
PAINT GREEN (3273 2325);
DISPLAY INVISIBLE (3273 2325);
FORCEADD TAP..1
(3275 2175);
FORCEPROP 3 LASTPIN (3225 2175) SIG_NAME UPI_CPU1_CPU0_P1P0_DN<13>
J 0
(3235 2185);
DISPLAY 0.659574 (3235 2185);
PAINT MONO (3235 2185);
DISPLAY INVISIBLE (3235 2185);
FORCEPROP 1 LASTPIN (3225 2175) BN 13
J 0
(3213 2183);
DISPLAY 0.680851 (3213 2183);
PAINT GREEN (3213 2183);
FORCEPROP 2 LAST CDS_LIB standard
J 0
(3275 2175);
PAINT MONO (3275 2175);
DISPLAY INVISIBLE (3275 2175);
FORCEPROP 1 LAST BODY_TYPE PLUMBING
J 0
(3275 2225);
DISPLAY 0.872340 (3275 2225);
PAINT GREEN (3275 2225);
DISPLAY INVISIBLE (3275 2225);
FORCEPROP 1 LAST HDL_TAP TRUE
J 0
(3600 2050);
DISPLAY 0.872340 (3600 2050);
DISPLAY INVISIBLE (3600 2050);
FORCEPROP 1 LAST PATH I68
J 0
(3273 2175);
DISPLAY 0.872340 (3273 2175);
PAINT GREEN (3273 2175);
DISPLAY INVISIBLE (3273 2175);
FORCEADD TAP..1
(3275 2275);
FORCEPROP 3 LASTPIN (3225 2275) SIG_NAME UPI_CPU1_CPU0_P1P0_DN<15>
J 0
(3235 2285);
DISPLAY 0.659574 (3235 2285);
PAINT MONO (3235 2285);
DISPLAY INVISIBLE (3235 2285);
FORCEPROP 1 LASTPIN (3225 2275) BN 15
J 0
(3213 2283);
DISPLAY 0.680851 (3213 2283);
PAINT GREEN (3213 2283);
FORCEPROP 2 LAST CDS_LIB standard
J 0
(3275 2275);
PAINT MONO (3275 2275);
DISPLAY INVISIBLE (3275 2275);
FORCEPROP 1 LAST BODY_TYPE PLUMBING
J 0
(3275 2325);
DISPLAY 0.872340 (3275 2325);
PAINT GREEN (3275 2325);
DISPLAY INVISIBLE (3275 2325);
FORCEPROP 1 LAST HDL_TAP TRUE
J 0
(3600 2150);
DISPLAY 0.872340 (3600 2150);
DISPLAY INVISIBLE (3600 2150);
FORCEPROP 1 LAST PATH I69
J 0
(3273 2275);
DISPLAY 0.872340 (3273 2275);
PAINT GREEN (3273 2275);
DISPLAY INVISIBLE (3273 2275);
FORCEADD TAP..1
(3275 2575);
FORCEPROP 3 LASTPIN (3225 2575) SIG_NAME UPI_CPU1_CPU0_P1P0_DN<21>
J 0
(3235 2585);
DISPLAY 0.659574 (3235 2585);
PAINT MONO (3235 2585);
DISPLAY INVISIBLE (3235 2585);
FORCEPROP 1 LASTPIN (3225 2575) BN 21
J 0
(3213 2583);
DISPLAY 0.680851 (3213 2583);
PAINT GREEN (3213 2583);
FORCEPROP 2 LAST CDS_LIB standard
J 0
(3275 2575);
DISPLAY INVISIBLE (3275 2575);
FORCEPROP 1 LAST BODY_TYPE PLUMBING
J 0
(3275 2625);
DISPLAY 0.872340 (3275 2625);
PAINT GREEN (3275 2625);
DISPLAY INVISIBLE (3275 2625);
FORCEPROP 1 LAST HDL_TAP TRUE
J 0
(3600 2450);
DISPLAY 0.872340 (3600 2450);
DISPLAY INVISIBLE (3600 2450);
FORCEPROP 1 LAST PATH I70
J 0
(3273 2575);
DISPLAY 0.872340 (3273 2575);
PAINT GREEN (3273 2575);
DISPLAY INVISIBLE (3273 2575);
FORCEADD TAP..1
(3275 2625);
FORCEPROP 3 LASTPIN (3225 2625) SIG_NAME UPI_CPU1_CPU0_P1P0_DN<22>
J 0
(3235 2635);
DISPLAY 0.659574 (3235 2635);
PAINT MONO (3235 2635);
DISPLAY INVISIBLE (3235 2635);
FORCEPROP 1 LASTPIN (3225 2625) BN 22
J 0
(3213 2633);
DISPLAY 0.680851 (3213 2633);
PAINT GREEN (3213 2633);
FORCEPROP 2 LAST CDS_LIB standard
J 0
(3275 2625);
DISPLAY INVISIBLE (3275 2625);
FORCEPROP 1 LAST BODY_TYPE PLUMBING
J 0
(3275 2675);
DISPLAY 0.872340 (3275 2675);
PAINT GREEN (3275 2675);
DISPLAY INVISIBLE (3275 2675);
FORCEPROP 1 LAST HDL_TAP TRUE
J 0
(3600 2500);
DISPLAY 0.872340 (3600 2500);
DISPLAY INVISIBLE (3600 2500);
FORCEPROP 1 LAST PATH I71
J 0
(3273 2625);
DISPLAY 0.872340 (3273 2625);
PAINT GREEN (3273 2625);
DISPLAY INVISIBLE (3273 2625);
FORCEADD TAP..1
(3275 2525);
FORCEPROP 3 LASTPIN (3225 2525) SIG_NAME UPI_CPU1_CPU0_P1P0_DN<20>
J 0
(3235 2535);
DISPLAY 0.659574 (3235 2535);
PAINT MONO (3235 2535);
DISPLAY INVISIBLE (3235 2535);
FORCEPROP 1 LASTPIN (3225 2525) BN 20
J 0
(3213 2533);
DISPLAY 0.680851 (3213 2533);
PAINT GREEN (3213 2533);
FORCEPROP 2 LAST CDS_LIB standard
J 0
(3275 2525);
DISPLAY INVISIBLE (3275 2525);
FORCEPROP 1 LAST BODY_TYPE PLUMBING
J 0
(3275 2575);
DISPLAY 0.872340 (3275 2575);
PAINT GREEN (3275 2575);
DISPLAY INVISIBLE (3275 2575);
FORCEPROP 1 LAST HDL_TAP TRUE
J 0
(3600 2400);
DISPLAY 0.872340 (3600 2400);
DISPLAY INVISIBLE (3600 2400);
FORCEPROP 1 LAST PATH I72
J 0
(3273 2525);
DISPLAY 0.872340 (3273 2525);
PAINT GREEN (3273 2525);
DISPLAY INVISIBLE (3273 2525);
FORCEADD TAP..1
(3275 2475);
FORCEPROP 3 LASTPIN (3225 2475) SIG_NAME UPI_CPU1_CPU0_P1P0_DN<19>
J 0
(3235 2485);
DISPLAY 0.659574 (3235 2485);
PAINT MONO (3235 2485);
DISPLAY INVISIBLE (3235 2485);
FORCEPROP 1 LASTPIN (3225 2475) BN 19
J 0
(3213 2483);
DISPLAY 0.680851 (3213 2483);
PAINT GREEN (3213 2483);
FORCEPROP 2 LAST CDS_LIB standard
J 0
(3275 2475);
DISPLAY INVISIBLE (3275 2475);
FORCEPROP 1 LAST BODY_TYPE PLUMBING
J 0
(3275 2525);
DISPLAY 0.872340 (3275 2525);
PAINT GREEN (3275 2525);
DISPLAY INVISIBLE (3275 2525);
FORCEPROP 1 LAST HDL_TAP TRUE
J 0
(3600 2350);
DISPLAY 0.872340 (3600 2350);
DISPLAY INVISIBLE (3600 2350);
FORCEPROP 1 LAST PATH I73
J 0
(3273 2475);
DISPLAY 0.872340 (3273 2475);
PAINT GREEN (3273 2475);
DISPLAY INVISIBLE (3273 2475);
FORCEADD TAP..1
(3275 2425);
FORCEPROP 3 LASTPIN (3225 2425) SIG_NAME UPI_CPU1_CPU0_P1P0_DN<18>
J 0
(3235 2435);
DISPLAY 0.659574 (3235 2435);
PAINT MONO (3235 2435);
DISPLAY INVISIBLE (3235 2435);
FORCEPROP 1 LASTPIN (3225 2425) BN 18
J 0
(3213 2433);
DISPLAY 0.680851 (3213 2433);
PAINT GREEN (3213 2433);
FORCEPROP 2 LAST CDS_LIB standard
J 0
(3275 2425);
DISPLAY INVISIBLE (3275 2425);
FORCEPROP 1 LAST BODY_TYPE PLUMBING
J 0
(3275 2475);
DISPLAY 0.872340 (3275 2475);
PAINT GREEN (3275 2475);
DISPLAY INVISIBLE (3275 2475);
FORCEPROP 1 LAST HDL_TAP TRUE
J 0
(3600 2300);
DISPLAY 0.872340 (3600 2300);
DISPLAY INVISIBLE (3600 2300);
FORCEPROP 1 LAST PATH I74
J 0
(3273 2425);
DISPLAY 0.872340 (3273 2425);
PAINT GREEN (3273 2425);
DISPLAY INVISIBLE (3273 2425);
FORCEADD TAP..1
(3275 2775);
FORCEPROP 3 LASTPIN (3225 2775) SIG_NAME UPI_CPU1_CPU0_P1P0_DP<0>
J 0
(3235 2785);
DISPLAY 0.659574 (3235 2785);
PAINT MONO (3235 2785);
DISPLAY INVISIBLE (3235 2785);
FORCEPROP 1 LASTPIN (3225 2775) BN 0
J 0
(3213 2783);
DISPLAY 0.680851 (3213 2783);
PAINT GREEN (3213 2783);
FORCEPROP 2 LAST CDS_LIB standard
J 0
(3275 2775);
PAINT MONO (3275 2775);
DISPLAY INVISIBLE (3275 2775);
FORCEPROP 1 LAST BODY_TYPE PLUMBING
J 0
(3275 2825);
DISPLAY 0.872340 (3275 2825);
PAINT GREEN (3275 2825);
DISPLAY INVISIBLE (3275 2825);
FORCEPROP 1 LAST HDL_TAP TRUE
J 0
(3600 2650);
DISPLAY 0.872340 (3600 2650);
DISPLAY INVISIBLE (3600 2650);
FORCEPROP 1 LAST PATH I75
J 0
(3273 2775);
DISPLAY 0.872340 (3273 2775);
PAINT GREEN (3273 2775);
DISPLAY INVISIBLE (3273 2775);
FORCEADD TAP..1
(3275 2875);
FORCEPROP 3 LASTPIN (3225 2875) SIG_NAME UPI_CPU1_CPU0_P1P0_DP<2>
J 0
(3235 2885);
DISPLAY 0.659574 (3235 2885);
PAINT MONO (3235 2885);
DISPLAY INVISIBLE (3235 2885);
FORCEPROP 1 LASTPIN (3225 2875) BN 2
J 0
(3213 2883);
DISPLAY 0.680851 (3213 2883);
PAINT GREEN (3213 2883);
FORCEPROP 2 LAST CDS_LIB standard
J 0
(3275 2875);
PAINT MONO (3275 2875);
DISPLAY INVISIBLE (3275 2875);
FORCEPROP 1 LAST BODY_TYPE PLUMBING
J 0
(3275 2925);
DISPLAY 0.872340 (3275 2925);
PAINT GREEN (3275 2925);
DISPLAY INVISIBLE (3275 2925);
FORCEPROP 1 LAST HDL_TAP TRUE
J 0
(3600 2750);
DISPLAY 0.872340 (3600 2750);
DISPLAY INVISIBLE (3600 2750);
FORCEPROP 1 LAST PATH I76
J 0
(3273 2875);
DISPLAY 0.872340 (3273 2875);
PAINT GREEN (3273 2875);
DISPLAY INVISIBLE (3273 2875);
FORCEADD TAP..1
(3275 2825);
FORCEPROP 3 LASTPIN (3225 2825) SIG_NAME UPI_CPU1_CPU0_P1P0_DP<1>
J 0
(3235 2835);
DISPLAY 0.659574 (3235 2835);
PAINT MONO (3235 2835);
DISPLAY INVISIBLE (3235 2835);
FORCEPROP 1 LASTPIN (3225 2825) BN 1
J 0
(3213 2833);
DISPLAY 0.680851 (3213 2833);
PAINT GREEN (3213 2833);
FORCEPROP 2 LAST CDS_LIB standard
J 0
(3275 2825);
PAINT MONO (3275 2825);
DISPLAY INVISIBLE (3275 2825);
FORCEPROP 1 LAST BODY_TYPE PLUMBING
J 0
(3275 2875);
DISPLAY 0.872340 (3275 2875);
PAINT GREEN (3275 2875);
DISPLAY INVISIBLE (3275 2875);
FORCEPROP 1 LAST HDL_TAP TRUE
J 0
(3600 2700);
DISPLAY 0.872340 (3600 2700);
DISPLAY INVISIBLE (3600 2700);
FORCEPROP 1 LAST PATH I77
J 0
(3273 2825);
DISPLAY 0.872340 (3273 2825);
PAINT GREEN (3273 2825);
DISPLAY INVISIBLE (3273 2825);
FORCEADD TAP..1
(3275 2675);
FORCEPROP 3 LASTPIN (3225 2675) SIG_NAME UPI_CPU1_CPU0_P1P0_DN<23>
J 0
(3235 2685);
DISPLAY 0.659574 (3235 2685);
PAINT MONO (3235 2685);
DISPLAY INVISIBLE (3235 2685);
FORCEPROP 1 LASTPIN (3225 2675) BN 23
J 0
(3213 2683);
DISPLAY 0.680851 (3213 2683);
PAINT GREEN (3213 2683);
FORCEPROP 2 LAST CDS_LIB standard
J 0
(3275 2675);
DISPLAY INVISIBLE (3275 2675);
FORCEPROP 1 LAST BODY_TYPE PLUMBING
J 0
(3275 2725);
DISPLAY 0.872340 (3275 2725);
PAINT GREEN (3275 2725);
DISPLAY INVISIBLE (3275 2725);
FORCEPROP 1 LAST HDL_TAP TRUE
J 0
(3600 2550);
DISPLAY 0.872340 (3600 2550);
DISPLAY INVISIBLE (3600 2550);
FORCEPROP 1 LAST PATH I78
J 0
(3273 2675);
DISPLAY 0.872340 (3273 2675);
PAINT GREEN (3273 2675);
DISPLAY INVISIBLE (3273 2675);
FORCEADD TAP..1
(3275 3125);
FORCEPROP 3 LASTPIN (3225 3125) SIG_NAME UPI_CPU1_CPU0_P1P0_DP<7>
J 0
(3235 3135);
DISPLAY 0.659574 (3235 3135);
PAINT MONO (3235 3135);
DISPLAY INVISIBLE (3235 3135);
FORCEPROP 1 LASTPIN (3225 3125) BN 7
J 0
(3213 3133);
DISPLAY 0.680851 (3213 3133);
PAINT GREEN (3213 3133);
FORCEPROP 2 LAST CDS_LIB standard
J 0
(3275 3125);
PAINT MONO (3275 3125);
DISPLAY INVISIBLE (3275 3125);
FORCEPROP 1 LAST BODY_TYPE PLUMBING
J 0
(3275 3175);
DISPLAY 0.872340 (3275 3175);
PAINT GREEN (3275 3175);
DISPLAY INVISIBLE (3275 3175);
FORCEPROP 1 LAST HDL_TAP TRUE
J 0
(3600 3000);
DISPLAY 0.872340 (3600 3000);
DISPLAY INVISIBLE (3600 3000);
FORCEPROP 1 LAST PATH I79
J 0
(3273 3125);
DISPLAY 0.872340 (3273 3125);
PAINT GREEN (3273 3125);
DISPLAY INVISIBLE (3273 3125);
FORCEADD TAP..1
(3275 3075);
FORCEPROP 3 LASTPIN (3225 3075) SIG_NAME UPI_CPU1_CPU0_P1P0_DP<6>
J 0
(3235 3085);
DISPLAY 0.659574 (3235 3085);
PAINT MONO (3235 3085);
DISPLAY INVISIBLE (3235 3085);
FORCEPROP 1 LASTPIN (3225 3075) BN 6
J 0
(3213 3083);
DISPLAY 0.680851 (3213 3083);
PAINT GREEN (3213 3083);
FORCEPROP 2 LAST CDS_LIB standard
J 0
(3275 3075);
PAINT MONO (3275 3075);
DISPLAY INVISIBLE (3275 3075);
FORCEPROP 1 LAST BODY_TYPE PLUMBING
J 0
(3275 3125);
DISPLAY 0.872340 (3275 3125);
PAINT GREEN (3275 3125);
DISPLAY INVISIBLE (3275 3125);
FORCEPROP 1 LAST HDL_TAP TRUE
J 0
(3600 2950);
DISPLAY 0.872340 (3600 2950);
DISPLAY INVISIBLE (3600 2950);
FORCEPROP 1 LAST PATH I80
J 0
(3273 3075);
DISPLAY 0.872340 (3273 3075);
PAINT GREEN (3273 3075);
DISPLAY INVISIBLE (3273 3075);
FORCEADD TAP..1
(3275 2975);
FORCEPROP 3 LASTPIN (3225 2975) SIG_NAME UPI_CPU1_CPU0_P1P0_DP<4>
J 0
(3235 2985);
DISPLAY 0.659574 (3235 2985);
PAINT MONO (3235 2985);
DISPLAY INVISIBLE (3235 2985);
FORCEPROP 1 LASTPIN (3225 2975) BN 4
J 0
(3213 2983);
DISPLAY 0.680851 (3213 2983);
PAINT GREEN (3213 2983);
FORCEPROP 2 LAST CDS_LIB standard
J 0
(3275 2975);
PAINT MONO (3275 2975);
DISPLAY INVISIBLE (3275 2975);
FORCEPROP 1 LAST BODY_TYPE PLUMBING
J 0
(3275 3025);
DISPLAY 0.872340 (3275 3025);
PAINT GREEN (3275 3025);
DISPLAY INVISIBLE (3275 3025);
FORCEPROP 1 LAST HDL_TAP TRUE
J 0
(3600 2850);
DISPLAY 0.872340 (3600 2850);
DISPLAY INVISIBLE (3600 2850);
FORCEPROP 1 LAST PATH I81
J 0
(3273 2975);
DISPLAY 0.872340 (3273 2975);
PAINT GREEN (3273 2975);
DISPLAY INVISIBLE (3273 2975);
FORCEADD TAP..1
(3275 2925);
FORCEPROP 3 LASTPIN (3225 2925) SIG_NAME UPI_CPU1_CPU0_P1P0_DP<3>
J 0
(3235 2935);
DISPLAY 0.659574 (3235 2935);
PAINT MONO (3235 2935);
DISPLAY INVISIBLE (3235 2935);
FORCEPROP 1 LASTPIN (3225 2925) BN 3
J 0
(3213 2933);
DISPLAY 0.680851 (3213 2933);
PAINT GREEN (3213 2933);
FORCEPROP 2 LAST CDS_LIB standard
J 0
(3275 2925);
PAINT MONO (3275 2925);
DISPLAY INVISIBLE (3275 2925);
FORCEPROP 1 LAST BODY_TYPE PLUMBING
J 0
(3275 2975);
DISPLAY 0.872340 (3275 2975);
PAINT GREEN (3275 2975);
DISPLAY INVISIBLE (3275 2975);
FORCEPROP 1 LAST HDL_TAP TRUE
J 0
(3600 2800);
DISPLAY 0.872340 (3600 2800);
DISPLAY INVISIBLE (3600 2800);
FORCEPROP 1 LAST PATH I82
J 0
(3273 2925);
DISPLAY 0.872340 (3273 2925);
PAINT GREEN (3273 2925);
DISPLAY INVISIBLE (3273 2925);
FORCEADD TAP..1
(3275 3025);
FORCEPROP 3 LASTPIN (3225 3025) SIG_NAME UPI_CPU1_CPU0_P1P0_DP<5>
J 0
(3235 3035);
DISPLAY 0.659574 (3235 3035);
PAINT MONO (3235 3035);
DISPLAY INVISIBLE (3235 3035);
FORCEPROP 1 LASTPIN (3225 3025) BN 5
J 0
(3213 3033);
DISPLAY 0.680851 (3213 3033);
PAINT GREEN (3213 3033);
FORCEPROP 2 LAST CDS_LIB standard
J 0
(3275 3025);
PAINT MONO (3275 3025);
DISPLAY INVISIBLE (3275 3025);
FORCEPROP 1 LAST BODY_TYPE PLUMBING
J 0
(3275 3075);
DISPLAY 0.872340 (3275 3075);
PAINT GREEN (3275 3075);
DISPLAY INVISIBLE (3275 3075);
FORCEPROP 1 LAST HDL_TAP TRUE
J 0
(3600 2900);
DISPLAY 0.872340 (3600 2900);
DISPLAY INVISIBLE (3600 2900);
FORCEPROP 1 LAST PATH I83
J 0
(3273 3025);
DISPLAY 0.872340 (3273 3025);
PAINT GREEN (3273 3025);
DISPLAY INVISIBLE (3273 3025);
FORCEADD TAP..1
(3275 3325);
FORCEPROP 3 LASTPIN (3225 3325) SIG_NAME UPI_CPU1_CPU0_P1P0_DP<11>
J 0
(3235 3335);
DISPLAY 0.659574 (3235 3335);
PAINT MONO (3235 3335);
DISPLAY INVISIBLE (3235 3335);
FORCEPROP 1 LASTPIN (3225 3325) BN 11
J 0
(3213 3333);
DISPLAY 0.680851 (3213 3333);
PAINT GREEN (3213 3333);
FORCEPROP 2 LAST CDS_LIB standard
J 0
(3275 3325);
PAINT MONO (3275 3325);
DISPLAY INVISIBLE (3275 3325);
FORCEPROP 1 LAST BODY_TYPE PLUMBING
J 0
(3275 3375);
DISPLAY 0.872340 (3275 3375);
PAINT GREEN (3275 3375);
DISPLAY INVISIBLE (3275 3375);
FORCEPROP 1 LAST HDL_TAP TRUE
J 0
(3600 3200);
DISPLAY 0.872340 (3600 3200);
DISPLAY INVISIBLE (3600 3200);
FORCEPROP 1 LAST PATH I84
J 0
(3273 3325);
DISPLAY 0.872340 (3273 3325);
PAINT GREEN (3273 3325);
DISPLAY INVISIBLE (3273 3325);
FORCEADD TAP..1
(3275 3375);
FORCEPROP 3 LASTPIN (3225 3375) SIG_NAME UPI_CPU1_CPU0_P1P0_DP<12>
J 0
(3235 3385);
DISPLAY 0.659574 (3235 3385);
PAINT MONO (3235 3385);
DISPLAY INVISIBLE (3235 3385);
FORCEPROP 1 LASTPIN (3225 3375) BN 12
J 0
(3213 3383);
DISPLAY 0.680851 (3213 3383);
PAINT GREEN (3213 3383);
FORCEPROP 2 LAST CDS_LIB standard
J 0
(3275 3375);
PAINT MONO (3275 3375);
DISPLAY INVISIBLE (3275 3375);
FORCEPROP 1 LAST BODY_TYPE PLUMBING
J 0
(3275 3425);
DISPLAY 0.872340 (3275 3425);
PAINT GREEN (3275 3425);
DISPLAY INVISIBLE (3275 3425);
FORCEPROP 1 LAST HDL_TAP TRUE
J 0
(3600 3250);
DISPLAY 0.872340 (3600 3250);
DISPLAY INVISIBLE (3600 3250);
FORCEPROP 1 LAST PATH I85
J 0
(3273 3375);
DISPLAY 0.872340 (3273 3375);
PAINT GREEN (3273 3375);
DISPLAY INVISIBLE (3273 3375);
FORCEADD TAP..1
(3275 3175);
FORCEPROP 3 LASTPIN (3225 3175) SIG_NAME UPI_CPU1_CPU0_P1P0_DP<8>
J 0
(3235 3185);
DISPLAY 0.659574 (3235 3185);
PAINT MONO (3235 3185);
DISPLAY INVISIBLE (3235 3185);
FORCEPROP 1 LASTPIN (3225 3175) BN 8
J 0
(3213 3183);
DISPLAY 0.680851 (3213 3183);
PAINT GREEN (3213 3183);
FORCEPROP 2 LAST CDS_LIB standard
J 0
(3275 3175);
PAINT MONO (3275 3175);
DISPLAY INVISIBLE (3275 3175);
FORCEPROP 1 LAST BODY_TYPE PLUMBING
J 0
(3275 3225);
DISPLAY 0.872340 (3275 3225);
PAINT GREEN (3275 3225);
DISPLAY INVISIBLE (3275 3225);
FORCEPROP 1 LAST HDL_TAP TRUE
J 0
(3600 3050);
DISPLAY 0.872340 (3600 3050);
DISPLAY INVISIBLE (3600 3050);
FORCEPROP 1 LAST PATH I86
J 0
(3273 3175);
DISPLAY 0.872340 (3273 3175);
PAINT GREEN (3273 3175);
DISPLAY INVISIBLE (3273 3175);
FORCEADD TAP..1
(3275 3275);
FORCEPROP 3 LASTPIN (3225 3275) SIG_NAME UPI_CPU1_CPU0_P1P0_DP<10>
J 0
(3235 3285);
DISPLAY 0.659574 (3235 3285);
PAINT MONO (3235 3285);
DISPLAY INVISIBLE (3235 3285);
FORCEPROP 1 LASTPIN (3225 3275) BN 10
J 0
(3213 3283);
DISPLAY 0.680851 (3213 3283);
PAINT GREEN (3213 3283);
FORCEPROP 2 LAST CDS_LIB standard
J 0
(3275 3275);
PAINT MONO (3275 3275);
DISPLAY INVISIBLE (3275 3275);
FORCEPROP 1 LAST BODY_TYPE PLUMBING
J 0
(3275 3325);
DISPLAY 0.872340 (3275 3325);
PAINT GREEN (3275 3325);
DISPLAY INVISIBLE (3275 3325);
FORCEPROP 1 LAST HDL_TAP TRUE
J 0
(3600 3150);
DISPLAY 0.872340 (3600 3150);
DISPLAY INVISIBLE (3600 3150);
FORCEPROP 1 LAST PATH I87
J 0
(3273 3275);
DISPLAY 0.872340 (3273 3275);
PAINT GREEN (3273 3275);
DISPLAY INVISIBLE (3273 3275);
FORCEADD TAP..1
(3275 3225);
FORCEPROP 3 LASTPIN (3225 3225) SIG_NAME UPI_CPU1_CPU0_P1P0_DP<9>
J 0
(3235 3235);
DISPLAY 0.659574 (3235 3235);
PAINT MONO (3235 3235);
DISPLAY INVISIBLE (3235 3235);
FORCEPROP 1 LASTPIN (3225 3225) BN 9
J 0
(3213 3233);
DISPLAY 0.680851 (3213 3233);
PAINT GREEN (3213 3233);
FORCEPROP 2 LAST CDS_LIB standard
J 0
(3275 3225);
PAINT MONO (3275 3225);
DISPLAY INVISIBLE (3275 3225);
FORCEPROP 1 LAST BODY_TYPE PLUMBING
J 0
(3275 3275);
DISPLAY 0.872340 (3275 3275);
PAINT GREEN (3275 3275);
DISPLAY INVISIBLE (3275 3275);
FORCEPROP 1 LAST HDL_TAP TRUE
J 0
(3600 3100);
DISPLAY 0.872340 (3600 3100);
DISPLAY INVISIBLE (3600 3100);
FORCEPROP 1 LAST PATH I88
J 0
(3273 3225);
DISPLAY 0.872340 (3273 3225);
PAINT GREEN (3273 3225);
DISPLAY INVISIBLE (3273 3225);
FORCEADD TAP..1
(3275 3425);
FORCEPROP 3 LASTPIN (3225 3425) SIG_NAME UPI_CPU1_CPU0_P1P0_DP<13>
J 0
(3235 3435);
DISPLAY 0.659574 (3235 3435);
PAINT MONO (3235 3435);
DISPLAY INVISIBLE (3235 3435);
FORCEPROP 1 LASTPIN (3225 3425) BN 13
J 0
(3213 3433);
DISPLAY 0.680851 (3213 3433);
PAINT GREEN (3213 3433);
FORCEPROP 2 LAST CDS_LIB standard
J 0
(3275 3425);
PAINT MONO (3275 3425);
DISPLAY INVISIBLE (3275 3425);
FORCEPROP 1 LAST BODY_TYPE PLUMBING
J 0
(3275 3475);
DISPLAY 0.872340 (3275 3475);
PAINT GREEN (3275 3475);
DISPLAY INVISIBLE (3275 3475);
FORCEPROP 1 LAST HDL_TAP TRUE
J 0
(3600 3300);
DISPLAY 0.872340 (3600 3300);
DISPLAY INVISIBLE (3600 3300);
FORCEPROP 1 LAST PATH I89
J 0
(3273 3425);
DISPLAY 0.872340 (3273 3425);
PAINT GREEN (3273 3425);
DISPLAY INVISIBLE (3273 3425);
FORCEADD TAP..1
(3275 3525);
FORCEPROP 3 LASTPIN (3225 3525) SIG_NAME UPI_CPU1_CPU0_P1P0_DP<15>
J 0
(3235 3535);
DISPLAY 0.659574 (3235 3535);
PAINT MONO (3235 3535);
DISPLAY INVISIBLE (3235 3535);
FORCEPROP 1 LASTPIN (3225 3525) BN 15
J 0
(3213 3533);
DISPLAY 0.680851 (3213 3533);
PAINT GREEN (3213 3533);
FORCEPROP 2 LAST CDS_LIB standard
J 0
(3275 3525);
PAINT MONO (3275 3525);
DISPLAY INVISIBLE (3275 3525);
FORCEPROP 1 LAST BODY_TYPE PLUMBING
J 0
(3275 3575);
DISPLAY 0.872340 (3275 3575);
PAINT GREEN (3275 3575);
DISPLAY INVISIBLE (3275 3575);
FORCEPROP 1 LAST HDL_TAP TRUE
J 0
(3600 3400);
DISPLAY 0.872340 (3600 3400);
DISPLAY INVISIBLE (3600 3400);
FORCEPROP 1 LAST PATH I90
J 0
(3273 3525);
DISPLAY 0.872340 (3273 3525);
PAINT GREEN (3273 3525);
DISPLAY INVISIBLE (3273 3525);
FORCEADD TAP..1
(3275 3475);
FORCEPROP 3 LASTPIN (3225 3475) SIG_NAME UPI_CPU1_CPU0_P1P0_DP<14>
J 0
(3235 3485);
DISPLAY 0.659574 (3235 3485);
PAINT MONO (3235 3485);
DISPLAY INVISIBLE (3235 3485);
FORCEPROP 1 LASTPIN (3225 3475) BN 14
J 0
(3213 3483);
DISPLAY 0.680851 (3213 3483);
PAINT GREEN (3213 3483);
FORCEPROP 2 LAST CDS_LIB standard
J 0
(3275 3475);
PAINT MONO (3275 3475);
DISPLAY INVISIBLE (3275 3475);
FORCEPROP 1 LAST BODY_TYPE PLUMBING
J 0
(3275 3525);
DISPLAY 0.872340 (3275 3525);
PAINT GREEN (3275 3525);
DISPLAY INVISIBLE (3275 3525);
FORCEPROP 1 LAST HDL_TAP TRUE
J 0
(3600 3350);
DISPLAY 0.872340 (3600 3350);
DISPLAY INVISIBLE (3600 3350);
FORCEPROP 1 LAST PATH I91
J 0
(3273 3475);
DISPLAY 0.872340 (3273 3475);
PAINT GREEN (3273 3475);
DISPLAY INVISIBLE (3273 3475);
FORCEADD TAP..1
(3275 3575);
FORCEPROP 3 LASTPIN (3225 3575) SIG_NAME UPI_CPU1_CPU0_P1P0_DP<16>
J 0
(3235 3585);
DISPLAY 0.659574 (3235 3585);
PAINT MONO (3235 3585);
DISPLAY INVISIBLE (3235 3585);
FORCEPROP 1 LASTPIN (3225 3575) BN 16
J 0
(3213 3583);
DISPLAY 0.680851 (3213 3583);
PAINT GREEN (3213 3583);
FORCEPROP 2 LAST CDS_LIB standard
J 0
(3275 3575);
PAINT MONO (3275 3575);
DISPLAY INVISIBLE (3275 3575);
FORCEPROP 1 LAST BODY_TYPE PLUMBING
J 0
(3275 3625);
DISPLAY 0.872340 (3275 3625);
PAINT GREEN (3275 3625);
DISPLAY INVISIBLE (3275 3625);
FORCEPROP 1 LAST HDL_TAP TRUE
J 0
(3600 3450);
DISPLAY 0.872340 (3600 3450);
DISPLAY INVISIBLE (3600 3450);
FORCEPROP 1 LAST PATH I92
J 0
(3273 3575);
DISPLAY 0.872340 (3273 3575);
PAINT GREEN (3273 3575);
DISPLAY INVISIBLE (3273 3575);
FORCEADD TAP..1
(3275 3625);
FORCEPROP 3 LASTPIN (3225 3625) SIG_NAME UPI_CPU1_CPU0_P1P0_DP<17>
J 0
(3235 3635);
DISPLAY 0.659574 (3235 3635);
PAINT MONO (3235 3635);
DISPLAY INVISIBLE (3235 3635);
FORCEPROP 1 LASTPIN (3225 3625) BN 17
J 0
(3213 3633);
DISPLAY 0.680851 (3213 3633);
PAINT GREEN (3213 3633);
FORCEPROP 2 LAST CDS_LIB standard
J 0
(3275 3625);
DISPLAY INVISIBLE (3275 3625);
FORCEPROP 1 LAST BODY_TYPE PLUMBING
J 0
(3275 3675);
DISPLAY 0.872340 (3275 3675);
PAINT GREEN (3275 3675);
DISPLAY INVISIBLE (3275 3675);
FORCEPROP 1 LAST HDL_TAP TRUE
J 0
(3600 3500);
DISPLAY 0.872340 (3600 3500);
DISPLAY INVISIBLE (3600 3500);
FORCEPROP 1 LAST PATH I93
J 0
(3273 3625);
DISPLAY 0.872340 (3273 3625);
PAINT GREEN (3273 3625);
DISPLAY INVISIBLE (3273 3625);
FORCEADD TAP..1
(3275 3675);
FORCEPROP 3 LASTPIN (3225 3675) SIG_NAME UPI_CPU1_CPU0_P1P0_DP<18>
J 0
(3235 3685);
DISPLAY 0.659574 (3235 3685);
PAINT MONO (3235 3685);
DISPLAY INVISIBLE (3235 3685);
FORCEPROP 1 LASTPIN (3225 3675) BN 18
J 0
(3213 3683);
DISPLAY 0.680851 (3213 3683);
PAINT GREEN (3213 3683);
FORCEPROP 2 LAST CDS_LIB standard
J 0
(3275 3675);
DISPLAY INVISIBLE (3275 3675);
FORCEPROP 1 LAST BODY_TYPE PLUMBING
J 0
(3275 3725);
DISPLAY 0.872340 (3275 3725);
PAINT GREEN (3275 3725);
DISPLAY INVISIBLE (3275 3725);
FORCEPROP 1 LAST HDL_TAP TRUE
J 0
(3600 3550);
DISPLAY 0.872340 (3600 3550);
DISPLAY INVISIBLE (3600 3550);
FORCEPROP 1 LAST PATH I94
J 0
(3273 3675);
DISPLAY 0.872340 (3273 3675);
PAINT GREEN (3273 3675);
DISPLAY INVISIBLE (3273 3675);
FORCEADD TAP..1
(3275 3925);
FORCEPROP 3 LASTPIN (3225 3925) SIG_NAME UPI_CPU1_CPU0_P1P0_DP<23>
J 0
(3235 3935);
DISPLAY 0.659574 (3235 3935);
PAINT MONO (3235 3935);
DISPLAY INVISIBLE (3235 3935);
FORCEPROP 1 LASTPIN (3225 3925) BN 23
J 0
(3213 3933);
DISPLAY 0.680851 (3213 3933);
PAINT GREEN (3213 3933);
FORCEPROP 2 LAST CDS_LIB standard
J 0
(3275 3925);
DISPLAY INVISIBLE (3275 3925);
FORCEPROP 1 LAST BODY_TYPE PLUMBING
J 0
(3275 3975);
DISPLAY 0.872340 (3275 3975);
PAINT GREEN (3275 3975);
DISPLAY INVISIBLE (3275 3975);
FORCEPROP 1 LAST HDL_TAP TRUE
J 0
(3600 3800);
DISPLAY 0.872340 (3600 3800);
DISPLAY INVISIBLE (3600 3800);
FORCEPROP 1 LAST PATH I95
J 0
(3273 3925);
DISPLAY 0.872340 (3273 3925);
PAINT GREEN (3273 3925);
DISPLAY INVISIBLE (3273 3925);
FORCEADD TAP..1
(3275 3875);
FORCEPROP 3 LASTPIN (3225 3875) SIG_NAME UPI_CPU1_CPU0_P1P0_DP<22>
J 0
(3235 3885);
DISPLAY 0.659574 (3235 3885);
PAINT MONO (3235 3885);
DISPLAY INVISIBLE (3235 3885);
FORCEPROP 1 LASTPIN (3225 3875) BN 22
J 0
(3213 3883);
DISPLAY 0.680851 (3213 3883);
PAINT GREEN (3213 3883);
FORCEPROP 2 LAST CDS_LIB standard
J 0
(3275 3875);
DISPLAY INVISIBLE (3275 3875);
FORCEPROP 1 LAST BODY_TYPE PLUMBING
J 0
(3275 3925);
DISPLAY 0.872340 (3275 3925);
PAINT GREEN (3275 3925);
DISPLAY INVISIBLE (3275 3925);
FORCEPROP 1 LAST HDL_TAP TRUE
J 0
(3600 3750);
DISPLAY 0.872340 (3600 3750);
DISPLAY INVISIBLE (3600 3750);
FORCEPROP 1 LAST PATH I96
J 0
(3273 3875);
DISPLAY 0.872340 (3273 3875);
PAINT GREEN (3273 3875);
DISPLAY INVISIBLE (3273 3875);
FORCEADD TAP..1
(3275 3825);
FORCEPROP 3 LASTPIN (3225 3825) SIG_NAME UPI_CPU1_CPU0_P1P0_DP<21>
J 0
(3235 3835);
DISPLAY 0.659574 (3235 3835);
PAINT MONO (3235 3835);
DISPLAY INVISIBLE (3235 3835);
FORCEPROP 1 LASTPIN (3225 3825) BN 21
J 0
(3213 3833);
DISPLAY 0.680851 (3213 3833);
PAINT GREEN (3213 3833);
FORCEPROP 2 LAST CDS_LIB standard
J 0
(3275 3825);
DISPLAY INVISIBLE (3275 3825);
FORCEPROP 1 LAST BODY_TYPE PLUMBING
J 0
(3275 3875);
DISPLAY 0.872340 (3275 3875);
PAINT GREEN (3275 3875);
DISPLAY INVISIBLE (3275 3875);
FORCEPROP 1 LAST HDL_TAP TRUE
J 0
(3600 3700);
DISPLAY 0.872340 (3600 3700);
DISPLAY INVISIBLE (3600 3700);
FORCEPROP 1 LAST PATH I97
J 0
(3273 3825);
DISPLAY 0.872340 (3273 3825);
PAINT GREEN (3273 3825);
DISPLAY INVISIBLE (3273 3825);
FORCEADD TAP..1
(3275 3725);
FORCEPROP 3 LASTPIN (3225 3725) SIG_NAME UPI_CPU1_CPU0_P1P0_DP<19>
J 0
(3235 3735);
DISPLAY 0.659574 (3235 3735);
PAINT MONO (3235 3735);
DISPLAY INVISIBLE (3235 3735);
FORCEPROP 1 LASTPIN (3225 3725) BN 19
J 0
(3213 3733);
DISPLAY 0.680851 (3213 3733);
PAINT GREEN (3213 3733);
FORCEPROP 2 LAST CDS_LIB standard
J 0
(3275 3725);
DISPLAY INVISIBLE (3275 3725);
FORCEPROP 1 LAST BODY_TYPE PLUMBING
J 0
(3275 3775);
DISPLAY 0.872340 (3275 3775);
PAINT GREEN (3275 3775);
DISPLAY INVISIBLE (3275 3775);
FORCEPROP 1 LAST HDL_TAP TRUE
J 0
(3600 3600);
DISPLAY 0.872340 (3600 3600);
DISPLAY INVISIBLE (3600 3600);
FORCEPROP 1 LAST PATH I98
J 0
(3273 3725);
DISPLAY 0.872340 (3273 3725);
PAINT GREEN (3273 3725);
DISPLAY INVISIBLE (3273 3725);
FORCEADD TAP..1
(3275 3775);
FORCEPROP 3 LASTPIN (3225 3775) SIG_NAME UPI_CPU1_CPU0_P1P0_DP<20>
J 0
(3235 3785);
DISPLAY 0.659574 (3235 3785);
PAINT MONO (3235 3785);
DISPLAY INVISIBLE (3235 3785);
FORCEPROP 1 LASTPIN (3225 3775) BN 20
J 0
(3213 3783);
DISPLAY 0.680851 (3213 3783);
PAINT GREEN (3213 3783);
FORCEPROP 2 LAST CDS_LIB standard
J 0
(3275 3775);
DISPLAY INVISIBLE (3275 3775);
FORCEPROP 1 LAST BODY_TYPE PLUMBING
J 0
(3275 3825);
DISPLAY 0.872340 (3275 3825);
PAINT GREEN (3275 3825);
DISPLAY INVISIBLE (3275 3825);
FORCEPROP 1 LAST HDL_TAP TRUE
J 0
(3600 3650);
DISPLAY 0.872340 (3600 3650);
DISPLAY INVISIBLE (3600 3650);
FORCEPROP 1 LAST PATH I99
J 0
(3273 3775);
DISPLAY 0.872340 (3273 3775);
PAINT GREEN (3273 3775);
DISPLAY INVISIBLE (3273 3775);
FORCEADD QUANTA_TITLE_BLOCK_C..1
(6200 -1575);
FORCEPROP 0 LAST CDS_CON_LAST_MODIFIED Fri Aug 25 14:00:45 2023
J 0
(4315 -1560);
PAINT MONO (4315 -1560);
DISPLAY INVISIBLE (4315 -1560);
FORCEPROP 1 LAST CUSTOM_TXT_CDS <CON_LAST_MODIFIED>
J 0
(4315 -1560);
DISPLAY 0.978723 (4315 -1560);
FORCEPROP 2 LAST CUSTOM_TXT_CDS <XR_PAGE_TITLE>
J 0
(-1690 3675);
DISPLAY 0.638298 (-1690 3675);
PAINT PINK (-1690 3675);
DISPLAY INVISIBLE (-1690 3675);
FORCEPROP 2 LAST CUSTOM_TXT_CDS <Q_NUMBER>
J 0
(4797 -1472);
DISPLAY 1.212766 (4797 -1472);
FORCEPROP 1 LAST CUSTOM_TXT_CDS <NAME_2>
J 0
(3025 -1525);
FORCEPROP 1 LAST CUSTOM_TXT_CDS <NAME_1>
J 0
(3025 -1400);
FORCEPROP 1 LAST CUSTOM_TXT_CDS <Q_PROJ>
J 0
(3818 -1473);
DISPLAY 1.212766 (3818 -1473);
FORCEPROP 1 LAST CUSTOM_TXT_CDS <Q_REV>
J 0
(6016 -1472);
DISPLAY 1.212766 (6016 -1472);
FORCEPROP 1 LAST CUSTOM_TXT_CDS <CON_PAGE_NUM> OF <CON_TOTAL_PAGES>
J 0
(5754 -1557);
DISPLAY 0.978723 (5754 -1557);
FORCEPROP 1 LAST Q_TITLE SPR CPU1 - UPI1 (21 OF 30)
J 0
(-3166 -1549);
DISPLAY 1.957447 (-3166 -1549);
PAINT GREEN (-3166 -1549);
FORCEPROP 1 LAST Q_DEPT 
J 1
(2437 -1526);
DISPLAY 1.957447 (2437 -1526);
PAINT GREEN (2437 -1526);
FORCEPROP 1 LAST COMMENT_BODY TRUE
J 0
(6212 -1588);
DISPLAY 0.978723 (6212 -1588);
PAINT GREEN (6212 -1588);
DISPLAY INVISIBLE (6212 -1588);
FORCEPROP 2 LAST CDS_XR_PAGE_TITLE CR-64 : @S9S_MB_2U_LIB.S9S_MB_2U(SCH_1):PAGE64
J 0
(-1690 3675);
DISPLAY 0.638298 (-1690 3675);
PAINT PINK (-1690 3675);
DISPLAY INVISIBLE (-1690 3675);
FORCEPROP 2 LAST PAGE_BORDER TRUE
J 0
(-1690 3675);
DISPLAY 0.638298 (-1690 3675);
PAINT PINK (-1690 3675);
DISPLAY INVISIBLE (-1690 3675);
FORCEPROP 1 LAST CDS_LMAN_SYM_OUTLINE -9475,6775,100,-125
J 0
(6200 -1575);
DISPLAY 0.468085 (6200 -1575);
PAINT GREEN (6200 -1575);
DISPLAY INVISIBLE (6200 -1575);
FORCEPROP 2 LAST CDS_LIB pure_quanta
J 0
(6200 -1575);
PAINT MONO (6200 -1575);
DISPLAY INVISIBLE (6200 -1575);
WIRE 17 -1 (3325 2800)(3325 2850);
WIRE 17 -1 (3325 2850)(3325 2900);
WIRE 17 -1 (3325 2900)(3325 2950);
WIRE 17 -1 (3325 2950)(3325 3000);
WIRE 17 -1 (3325 3000)(3325 3050);
WIRE 17 -1 (3325 3050)(3325 3100);
WIRE 17 -1 (3325 3100)(3325 3150);
WIRE 17 -1 (3325 3150)(3325 3200);
WIRE 17 -1 (3325 3200)(3325 3250);
WIRE 17 -1 (3325 3250)(3325 3300);
WIRE 17 -1 (3325 3300)(3325 3350);
WIRE 17 -1 (3325 3350)(3325 3400);
WIRE 17 -1 (3325 3400)(3325 3450);
WIRE 17 -1 (3325 3450)(3325 3500);
WIRE 17 -1 (3325 3500)(3325 3550);
WIRE 17 -1 (3325 3550)(3325 3600);
WIRE 17 -1 (3325 3600)(3325 3650);
WIRE 17 -1 (3325 3650)(3325 3700);
WIRE 17 -1 (3325 3700)(3325 3750);
WIRE 17 -1 (3325 3750)(3325 3800);
WIRE 17 -1 (3325 3800)(3325 3850);
WIRE 17 -1 (3325 3850)(3325 3900);
WIRE 17 -1 (3325 3900)(3325 3950);
WIRE 17 -1 (3325 3950)(4425 3950);
FORCEPROP 2 LAST SIG_NAME UPI_CPU1_CPU0_P1P0_DP<23:0>
J 0
(3465 3960);
DISPLAY 0.680851 (3465 3960);
PAINT WHITE (3465 3960);
WIRE 17 -1 (3325 1550)(3325 1600);
WIRE 17 -1 (3325 1600)(3325 1650);
WIRE 17 -1 (3325 1650)(3325 1700);
WIRE 17 -1 (3325 1700)(3325 1750);
WIRE 17 -1 (3325 1750)(3325 1800);
WIRE 17 -1 (3325 1800)(3325 1850);
WIRE 17 -1 (3325 1850)(3325 1900);
WIRE 17 -1 (3325 1900)(3325 1950);
WIRE 17 -1 (3325 2000)(3325 1950);
WIRE 17 -1 (3325 2000)(3325 2050);
WIRE 17 -1 (3325 2050)(3325 2100);
WIRE 17 -1 (3325 2100)(3325 2150);
WIRE 17 -1 (3325 2150)(3325 2200);
WIRE 17 -1 (3325 2200)(3325 2250);
WIRE 17 -1 (3325 2250)(3325 2300);
WIRE 17 -1 (3325 2300)(3325 2350);
WIRE 17 -1 (3325 2350)(3325 2400);
WIRE 17 -1 (3325 2400)(3325 2450);
WIRE 17 -1 (3325 2450)(3325 2500);
WIRE 17 -1 (3325 2500)(3325 2550);
WIRE 17 -1 (3325 2550)(3325 2600);
WIRE 17 -1 (3325 2600)(3325 2650);
WIRE 17 -1 (3325 2650)(3325 2700);
WIRE 17 -1 (3325 2700)(4425 2700);
FORCEPROP 2 LAST SIG_NAME UPI_CPU1_CPU0_P1P0_DN<23:0>
J 0
(3465 2710);
DISPLAY 0.680851 (3465 2710);
PAINT WHITE (3465 2710);
WIRE 17 -1 (-150 2800)(-150 2850);
WIRE 17 -1 (-150 2850)(-150 2900);
WIRE 17 -1 (-150 2900)(-150 2950);
WIRE 17 -1 (-150 2950)(-150 3000);
WIRE 17 -1 (-150 3000)(-150 3050);
WIRE 17 -1 (-150 3050)(-150 3100);
WIRE 17 -1 (-150 3100)(-150 3150);
WIRE 17 -1 (-150 3150)(-150 3200);
WIRE 17 -1 (-150 3200)(-150 3250);
WIRE 17 -1 (-150 3250)(-150 3300);
WIRE 17 -1 (-150 3300)(-150 3350);
WIRE 17 -1 (-150 3400)(-150 3350);
WIRE 17 -1 (-150 3450)(-150 3400);
WIRE 17 -1 (-150 3500)(-150 3450);
WIRE 17 -1 (-150 3500)(-150 3550);
WIRE 17 -1 (-150 3550)(-150 3600);
WIRE 17 -1 (-150 3600)(-150 3650);
WIRE 17 -1 (-150 3650)(-150 3700);
WIRE 17 -1 (-150 3700)(-150 3750);
WIRE 17 -1 (-150 3800)(-150 3750);
WIRE 17 -1 (-150 3850)(-150 3800);
WIRE 17 -1 (-150 3900)(-150 3850);
WIRE 17 -1 (-150 3950)(-150 3900);
WIRE 17 -1 (-1300 3950)(-150 3950);
FORCEPROP 2 LAST SIG_NAME UPI_CPU0_CPU1_P0P1_DP<23:0>
J 0
(-1185 3960);
DISPLAY 0.680851 (-1185 3960);
PAINT WHITE (-1185 3960);
WIRE 17 -1 (-150 1600)(-150 1550);
WIRE 17 -1 (-150 1650)(-150 1600);
WIRE 17 -1 (-150 1700)(-150 1650);
WIRE 17 -1 (-150 1750)(-150 1700);
WIRE 17 -1 (-150 1800)(-150 1750);
WIRE 17 -1 (-150 1850)(-150 1800);
WIRE 17 -1 (-150 1900)(-150 1850);
WIRE 17 -1 (-150 1950)(-150 1900);
WIRE 17 -1 (-150 2000)(-150 1950);
WIRE 17 -1 (-150 2050)(-150 2000);
WIRE 17 -1 (-150 2100)(-150 2050);
WIRE 17 -1 (-150 2150)(-150 2100);
WIRE 17 -1 (-150 2200)(-150 2150);
WIRE 17 -1 (-150 2200)(-150 2250);
WIRE 17 -1 (-150 2300)(-150 2250);
WIRE 17 -1 (-150 2350)(-150 2300);
WIRE 17 -1 (-150 2400)(-150 2350);
WIRE 17 -1 (-150 2450)(-150 2400);
WIRE 17 -1 (-150 2500)(-150 2450);
WIRE 17 -1 (-150 2500)(-150 2550);
WIRE 17 -1 (-150 2550)(-150 2600);
WIRE 17 -1 (-150 2600)(-150 2650);
WIRE 17 -1 (-150 2650)(-150 2700);
WIRE 17 -1 (-150 2725)(-150 2700);
WIRE 17 -1 (-1300 2725)(-150 2725);
FORCEPROP 2 LAST SIG_NAME UPI_CPU0_CPU1_P0P1_DN<23:0>
J 0
(-1285 2735);
DISPLAY 0.680851 (-1285 2735);
PAINT WHITE (-1285 2735);
WIRE 16 -1 (400 2675)(-50 2675);
WIRE 16 -1 (-50 2625)(400 2625);
WIRE 16 -1 (-50 2575)(400 2575);
WIRE 16 -1 (-50 2525)(400 2525);
WIRE 16 -1 (-50 2475)(400 2475);
WIRE 16 -1 (-50 2425)(400 2425);
WIRE 16 -1 (400 2375)(-50 2375);
WIRE 16 -1 (-50 2325)(400 2325);
WIRE 16 -1 (-50 2275)(400 2275);
WIRE 16 -1 (400 2225)(-50 2225);
WIRE 16 -1 (-50 2175)(400 2175);
WIRE 16 -1 (-50 2125)(400 2125);
WIRE 16 -1 (400 2075)(-50 2075);
WIRE 16 -1 (-50 2025)(400 2025);
WIRE 16 -1 (-50 1975)(400 1975);
WIRE 16 -1 (-50 1925)(400 1925);
WIRE 16 -1 (-50 1875)(400 1875);
WIRE 16 -1 (-50 1825)(400 1825);
WIRE 16 -1 (-50 1775)(400 1775);
WIRE 16 -1 (-50 1725)(400 1725);
WIRE 16 -1 (400 1675)(-50 1675);
WIRE 16 -1 (400 1625)(-50 1625);
WIRE 16 -1 (-50 1575)(400 1575);
WIRE 16 -1 (-50 1525)(400 1525);
WIRE 16 -1 (-50 3925)(400 3925);
WIRE 16 -1 (-50 3875)(400 3875);
WIRE 16 -1 (400 3825)(-50 3825);
WIRE 16 -1 (400 3775)(-50 3775);
WIRE 16 -1 (-50 3725)(400 3725);
WIRE 16 -1 (-50 3675)(400 3675);
WIRE 16 -1 (-50 3625)(400 3625);
WIRE 16 -1 (-50 3575)(400 3575);
WIRE 16 -1 (-50 3525)(400 3525);
WIRE 16 -1 (-50 3475)(400 3475);
WIRE 16 -1 (400 3425)(-50 3425);
WIRE 16 -1 (-50 3375)(400 3375);
WIRE 16 -1 (-50 3325)(400 3325);
WIRE 16 -1 (-50 3275)(400 3275);
WIRE 16 -1 (-50 3225)(400 3225);
WIRE 16 -1 (-50 3175)(400 3175);
WIRE 16 -1 (-50 3125)(400 3125);
WIRE 16 -1 (-50 3075)(400 3075);
WIRE 16 -1 (-50 3025)(400 3025);
WIRE 16 -1 (-50 2975)(400 2975);
WIRE 16 -1 (-50 2925)(400 2925);
WIRE 16 -1 (-50 2875)(400 2875);
WIRE 16 -1 (-50 2825)(400 2825);
WIRE 16 -1 (-50 2775)(400 2775);
WIRE 16 -1 (2800 2675)(3225 2675);
WIRE 16 -1 (2800 2625)(3225 2625);
WIRE 16 -1 (2800 2575)(3225 2575);
WIRE 16 -1 (2800 2525)(3225 2525);
WIRE 16 -1 (2800 2475)(3225 2475);
WIRE 16 -1 (2800 2425)(3225 2425);
WIRE 16 -1 (2800 2375)(3225 2375);
WIRE 16 -1 (2800 2325)(3225 2325);
WIRE 16 -1 (2800 2275)(3225 2275);
WIRE 16 -1 (2800 2225)(3225 2225);
WIRE 16 -1 (2800 2175)(3225 2175);
WIRE 16 -1 (2800 2125)(3225 2125);
WIRE 16 -1 (2800 2075)(3225 2075);
WIRE 16 -1 (2800 2025)(3225 2025);
WIRE 16 -1 (2800 1975)(3225 1975);
WIRE 16 -1 (2800 1925)(3225 1925);
WIRE 16 -1 (2800 1875)(3225 1875);
WIRE 16 -1 (2800 1825)(3225 1825);
WIRE 16 -1 (2800 1775)(3225 1775);
WIRE 16 -1 (2800 1725)(3225 1725);
WIRE 16 -1 (2800 1675)(3225 1675);
WIRE 16 -1 (2800 1625)(3225 1625);
WIRE 16 -1 (2800 1575)(3225 1575);
WIRE 16 -1 (2800 1525)(3225 1525);
WIRE 16 -1 (2800 3925)(3225 3925);
WIRE 16 -1 (2800 3875)(3225 3875);
WIRE 16 -1 (2800 3825)(3225 3825);
WIRE 16 -1 (2800 3775)(3225 3775);
WIRE 16 -1 (2800 3725)(3225 3725);
WIRE 16 -1 (2800 3675)(3225 3675);
WIRE 16 -1 (2800 3625)(3225 3625);
WIRE 16 -1 (2800 3575)(3225 3575);
WIRE 16 -1 (2800 3525)(3225 3525);
WIRE 16 -1 (2800 3475)(3225 3475);
WIRE 16 -1 (2800 3425)(3225 3425);
WIRE 16 -1 (2800 3375)(3225 3375);
WIRE 16 -1 (2800 3325)(3225 3325);
WIRE 16 -1 (2800 3275)(3225 3275);
WIRE 16 -1 (2800 3225)(3225 3225);
WIRE 16 -1 (2800 3175)(3225 3175);
WIRE 16 -1 (2800 3125)(3225 3125);
WIRE 16 -1 (2800 3075)(3225 3075);
WIRE 16 -1 (2800 3025)(3225 3025);
WIRE 16 -1 (2800 2975)(3225 2975);
WIRE 16 -1 (2800 2925)(3225 2925);
WIRE 16 -1 (2800 2875)(3225 2875);
WIRE 16 -1 (2800 2825)(3225 2825);
WIRE 16 -1 (2800 2775)(3225 2775);
QUIT
